G04 #@! TF.GenerationSoftware,KiCad,Pcbnew,(5.0.1)-3*
G04 #@! TF.CreationDate,2019-04-10T15:36:06+02:00*
G04 #@! TF.ProjectId,discovery,646973636F766572792E6B696361645F,rev?*
G04 #@! TF.SameCoordinates,PX4c4640PY8a48028*
G04 #@! TF.FileFunction,Copper,L2,Bot,Signal*
G04 #@! TF.FilePolarity,Positive*
%FSLAX46Y46*%
G04 Gerber Fmt 4.6, Leading zero omitted, Abs format (unit mm)*
%MOMM*%
%LPD*%
G01*
G04 APERTURE LIST*
G04 #@! TA.AperFunction,WasherPad*
%ADD10C,4.000000*%
G04 #@! TD*
G04 #@! TA.AperFunction,ComponentPad*
%ADD11C,2.500000*%
G04 #@! TD*
G04 #@! TA.AperFunction,ComponentPad*
%ADD12C,5.000000*%
G04 #@! TD*
G04 #@! TA.AperFunction,ComponentPad*
%ADD13C,15.000000*%
G04 #@! TD*
G04 #@! TA.AperFunction,Conductor*
%ADD14C,0.254000*%
G04 #@! TD*
G04 #@! TA.AperFunction,Conductor*
%ADD15C,0.124000*%
G04 #@! TD*
G04 APERTURE END LIST*
D10*
G04 #@! TO.P,J2,*
G04 #@! TO.N,*
X30101280Y53498440D03*
X30101280Y35698440D03*
D11*
G04 #@! TO.P,J2,1*
G04 #@! TO.N,+12V*
X25901280Y40398440D03*
G04 #@! TO.P,J2,2*
X25901280Y44598440D03*
G04 #@! TO.P,J2,3*
X25901280Y48798440D03*
G04 #@! TO.P,J2,4*
G04 #@! TO.N,GND*
X30101280Y40398440D03*
G04 #@! TO.P,J2,5*
X30101280Y44598440D03*
G04 #@! TO.P,J2,6*
X30101280Y48798440D03*
G04 #@! TD*
G04 #@! TO.P,J4,6*
G04 #@! TO.N,GND*
X5901280Y40398440D03*
G04 #@! TO.P,J4,5*
X5901280Y44598440D03*
G04 #@! TO.P,J4,4*
X5901280Y48798440D03*
G04 #@! TO.P,J4,3*
G04 #@! TO.N,+12V*
X10101280Y40398440D03*
G04 #@! TO.P,J4,2*
X10101280Y44598440D03*
G04 #@! TO.P,J4,1*
X10101280Y48798440D03*
D10*
G04 #@! TO.P,J4,*
G04 #@! TO.N,*
X5901280Y53498440D03*
X5901280Y35698440D03*
G04 #@! TD*
G04 #@! TO.P,J5,*
G04 #@! TO.N,*
X5901280Y6865840D03*
X5901280Y24665840D03*
D11*
G04 #@! TO.P,J5,1*
G04 #@! TO.N,+12V*
X10101280Y19965840D03*
G04 #@! TO.P,J5,2*
X10101280Y15765840D03*
G04 #@! TO.P,J5,3*
X10101280Y11565840D03*
G04 #@! TO.P,J5,4*
G04 #@! TO.N,GND*
X5901280Y19965840D03*
G04 #@! TO.P,J5,5*
X5901280Y15765840D03*
G04 #@! TO.P,J5,6*
X5901280Y11565840D03*
G04 #@! TD*
G04 #@! TO.P,J6,6*
G04 #@! TO.N,GND*
X30101280Y19965840D03*
G04 #@! TO.P,J6,5*
X30101280Y15765840D03*
G04 #@! TO.P,J6,4*
X30101280Y11565840D03*
G04 #@! TO.P,J6,3*
G04 #@! TO.N,+12V*
X25901280Y19965840D03*
G04 #@! TO.P,J6,2*
X25901280Y15765840D03*
G04 #@! TO.P,J6,1*
X25901280Y11565840D03*
D10*
G04 #@! TO.P,J6,*
G04 #@! TO.N,*
X30101280Y6865840D03*
X30101280Y24665840D03*
G04 #@! TD*
D11*
G04 #@! TO.P,J1,8*
G04 #@! TO.N,+12V*
X6101280Y66398440D03*
G04 #@! TO.P,J1,7*
X6101280Y70598440D03*
G04 #@! TO.P,J1,6*
X6101280Y74798440D03*
G04 #@! TO.P,J1,5*
X6101280Y78998440D03*
G04 #@! TO.P,J1,4*
G04 #@! TO.N,GND*
X10301280Y66398440D03*
G04 #@! TO.P,J1,3*
X10301280Y70598440D03*
G04 #@! TO.P,J1,2*
X10301280Y74798440D03*
G04 #@! TO.P,J1,1*
X10301280Y78998440D03*
D10*
G04 #@! TO.P,J1,*
G04 #@! TO.N,*
X5901280Y83698440D03*
X5901280Y61698440D03*
G04 #@! TD*
G04 #@! TO.P,J3,*
G04 #@! TO.N,*
X30101280Y83698440D03*
X30101280Y61698440D03*
D11*
G04 #@! TO.P,J3,1*
G04 #@! TO.N,GND*
X25701280Y66398440D03*
G04 #@! TO.P,J3,2*
X25701280Y70598440D03*
G04 #@! TO.P,J3,3*
X25701280Y74798440D03*
G04 #@! TO.P,J3,4*
X25701280Y78998440D03*
G04 #@! TO.P,J3,5*
G04 #@! TO.N,+12V*
X29901280Y66398440D03*
G04 #@! TO.P,J3,6*
X29901280Y70598440D03*
G04 #@! TO.P,J3,7*
X29901280Y74798440D03*
G04 #@! TO.P,J3,8*
X29901280Y78998440D03*
G04 #@! TD*
D12*
G04 #@! TO.P,W1,1*
G04 #@! TO.N,GND*
X140001280Y-1560D03*
G04 #@! TD*
G04 #@! TO.P,W2,1*
G04 #@! TO.N,GND*
X1280Y89998440D03*
G04 #@! TD*
G04 #@! TO.P,W3,1*
G04 #@! TO.N,GND*
X140001280Y89998440D03*
G04 #@! TD*
G04 #@! TO.P,W4,1*
G04 #@! TO.N,GND*
X1280Y-1560D03*
G04 #@! TD*
D13*
G04 #@! TO.P,W5,1*
G04 #@! TO.N,+12V*
X55001280Y77998440D03*
G04 #@! TD*
G04 #@! TO.P,W6,1*
G04 #@! TO.N,+12V*
X55001280Y55498440D03*
G04 #@! TD*
G04 #@! TO.P,W7,1*
G04 #@! TO.N,+12V*
X55001280Y32998440D03*
G04 #@! TD*
G04 #@! TO.P,W8,1*
G04 #@! TO.N,+12V*
X55001280Y10498440D03*
G04 #@! TD*
G04 #@! TO.P,W9,1*
G04 #@! TO.N,GND*
X115001280Y80748440D03*
G04 #@! TD*
G04 #@! TO.P,W10,1*
G04 #@! TO.N,GND*
X115001280Y58248440D03*
G04 #@! TD*
G04 #@! TO.P,W11,1*
G04 #@! TO.N,GND*
X115001280Y13248440D03*
G04 #@! TD*
G04 #@! TO.P,W12,1*
G04 #@! TO.N,GND*
X115001280Y35748440D03*
G04 #@! TD*
D14*
G04 #@! TO.N,GND*
G36*
X143799280Y92500555D02*
X143799281Y-2503674D01*
X142503396Y-3799560D01*
X-2500835Y-3799560D01*
X-3609414Y-2690981D01*
X-920374Y-2690981D01*
X-550566Y-2887738D01*
X553126Y-2887738D01*
X922934Y-2690981D01*
X139079626Y-2690981D01*
X139449434Y-2887738D01*
X140553126Y-2887738D01*
X140922934Y-2690981D01*
X140001280Y-1769327D01*
X139079626Y-2690981D01*
X922934Y-2690981D01*
X1280Y-1769327D01*
X-920374Y-2690981D01*
X-3609414Y-2690981D01*
X-3796720Y-2503676D01*
X-3796720Y550286D01*
X-2884898Y550286D01*
X-2884898Y-553406D01*
X-2688141Y-923214D01*
X-1766487Y-1560D01*
X1769047Y-1560D01*
X2690701Y-923214D01*
X2887458Y-553406D01*
X2887458Y550286D01*
X2690701Y920094D01*
X1769047Y-1560D01*
X-1766487Y-1560D01*
X-2688141Y920094D01*
X-2884898Y550286D01*
X-3796720Y550286D01*
X-3796720Y2687861D01*
X-920374Y2687861D01*
X1280Y1766207D01*
X922934Y2687861D01*
X553126Y2884618D01*
X-550566Y2884618D01*
X-920374Y2687861D01*
X-3796720Y2687861D01*
X-3796720Y7487839D01*
X2774280Y7487839D01*
X2774280Y6243841D01*
X3250337Y5094537D01*
X4129977Y4214897D01*
X5279281Y3738840D01*
X6523279Y3738840D01*
X7672583Y4214897D01*
X8552223Y5094537D01*
X9028280Y6243841D01*
X9028280Y7487839D01*
X26974280Y7487839D01*
X26974280Y6243841D01*
X27450337Y5094537D01*
X28329977Y4214897D01*
X29479281Y3738840D01*
X30723279Y3738840D01*
X31872583Y4214897D01*
X32752223Y5094537D01*
X33228280Y6243841D01*
X33228280Y7487839D01*
X32752223Y8637143D01*
X31872583Y9516783D01*
X30723279Y9992840D01*
X30549094Y9992840D01*
X30676561Y10106676D01*
X30101280Y10681957D01*
X29525999Y10106676D01*
X29653466Y9992840D01*
X29479281Y9992840D01*
X28329977Y9516783D01*
X27450337Y8637143D01*
X26974280Y7487839D01*
X9028280Y7487839D01*
X8552223Y8637143D01*
X7672583Y9516783D01*
X6523279Y9992840D01*
X6349094Y9992840D01*
X6476561Y10106676D01*
X5901280Y10681957D01*
X5325999Y10106676D01*
X5453466Y9992840D01*
X5279281Y9992840D01*
X4129977Y9516783D01*
X3250337Y8637143D01*
X2774280Y7487839D01*
X-3796720Y7487839D01*
X-3796720Y11318114D01*
X4255851Y11318114D01*
X4286301Y11165031D01*
X4442116Y10990559D01*
X5017397Y11565840D01*
X6785163Y11565840D01*
X7360444Y10990559D01*
X7516259Y11165031D01*
X7546709Y11813566D01*
X7516259Y11966649D01*
X7360444Y12141121D01*
X6785163Y11565840D01*
X5017397Y11565840D01*
X4442116Y12141121D01*
X4286301Y11966649D01*
X4255851Y11318114D01*
X-3796720Y11318114D01*
X-3796720Y13025004D01*
X5325999Y13025004D01*
X5901280Y12449723D01*
X6476561Y13025004D01*
X6302089Y13180819D01*
X5653554Y13211269D01*
X5500471Y13180819D01*
X5325999Y13025004D01*
X-3796720Y13025004D01*
X-3796720Y14306676D01*
X5325999Y14306676D01*
X5500471Y14150861D01*
X6149006Y14120411D01*
X6302089Y14150861D01*
X6476561Y14306676D01*
X5901280Y14881957D01*
X5325999Y14306676D01*
X-3796720Y14306676D01*
X-3796720Y15518114D01*
X4255851Y15518114D01*
X4286301Y15365031D01*
X4442116Y15190559D01*
X5017397Y15765840D01*
X6785163Y15765840D01*
X7360444Y15190559D01*
X7516259Y15365031D01*
X7546709Y16013566D01*
X7516259Y16166649D01*
X7360444Y16341121D01*
X6785163Y15765840D01*
X5017397Y15765840D01*
X4442116Y16341121D01*
X4286301Y16166649D01*
X4255851Y15518114D01*
X-3796720Y15518114D01*
X-3796720Y17225004D01*
X5325999Y17225004D01*
X5901280Y16649723D01*
X6476561Y17225004D01*
X6302089Y17380819D01*
X5653554Y17411269D01*
X5500471Y17380819D01*
X5325999Y17225004D01*
X-3796720Y17225004D01*
X-3796720Y18506676D01*
X5325999Y18506676D01*
X5500471Y18350861D01*
X6149006Y18320411D01*
X6302089Y18350861D01*
X6476561Y18506676D01*
X5901280Y19081957D01*
X5325999Y18506676D01*
X-3796720Y18506676D01*
X-3796720Y19718114D01*
X4255851Y19718114D01*
X4286301Y19565031D01*
X4442116Y19390559D01*
X5017397Y19965840D01*
X6785163Y19965840D01*
X7360444Y19390559D01*
X7516259Y19565031D01*
X7546709Y20213566D01*
X7516259Y20366649D01*
X7451953Y20438655D01*
X7724280Y20438655D01*
X7724280Y19493025D01*
X8086157Y18619378D01*
X8754818Y17950717D01*
X8959729Y17865840D01*
X8754818Y17780963D01*
X8086157Y17112302D01*
X7724280Y16238655D01*
X7724280Y15293025D01*
X8086157Y14419378D01*
X8754818Y13750717D01*
X8959729Y13665840D01*
X8754818Y13580963D01*
X8086157Y12912302D01*
X7724280Y12038655D01*
X7724280Y11093025D01*
X8086157Y10219378D01*
X8754818Y9550717D01*
X9628465Y9188840D01*
X10574095Y9188840D01*
X11447742Y9550717D01*
X12116403Y10219378D01*
X12478280Y11093025D01*
X12478280Y12038655D01*
X12116403Y12912302D01*
X11447742Y13580963D01*
X11242831Y13665840D01*
X11447742Y13750717D01*
X12116403Y14419378D01*
X12478280Y15293025D01*
X12478280Y16238655D01*
X12116403Y17112302D01*
X11447742Y17780963D01*
X11242831Y17865840D01*
X11447742Y17950717D01*
X12116403Y18619378D01*
X12478280Y19493025D01*
X12478280Y20438655D01*
X23524280Y20438655D01*
X23524280Y19493025D01*
X23886157Y18619378D01*
X24554818Y17950717D01*
X24759729Y17865840D01*
X24554818Y17780963D01*
X23886157Y17112302D01*
X23524280Y16238655D01*
X23524280Y15293025D01*
X23886157Y14419378D01*
X24554818Y13750717D01*
X24759729Y13665840D01*
X24554818Y13580963D01*
X23886157Y12912302D01*
X23524280Y12038655D01*
X23524280Y11093025D01*
X23886157Y10219378D01*
X24554818Y9550717D01*
X25428465Y9188840D01*
X26374095Y9188840D01*
X27247742Y9550717D01*
X27916403Y10219378D01*
X28278280Y11093025D01*
X28278280Y11318114D01*
X28455851Y11318114D01*
X28486301Y11165031D01*
X28642116Y10990559D01*
X29217397Y11565840D01*
X30985163Y11565840D01*
X31560444Y10990559D01*
X31716259Y11165031D01*
X31746709Y11813566D01*
X31716259Y11966649D01*
X31560444Y12141121D01*
X30985163Y11565840D01*
X29217397Y11565840D01*
X28642116Y12141121D01*
X28486301Y11966649D01*
X28455851Y11318114D01*
X28278280Y11318114D01*
X28278280Y12038655D01*
X27916403Y12912302D01*
X27803701Y13025004D01*
X29525999Y13025004D01*
X30101280Y12449723D01*
X30676561Y13025004D01*
X30502089Y13180819D01*
X29853554Y13211269D01*
X29700471Y13180819D01*
X29525999Y13025004D01*
X27803701Y13025004D01*
X27247742Y13580963D01*
X27042831Y13665840D01*
X27247742Y13750717D01*
X27803701Y14306676D01*
X29525999Y14306676D01*
X29700471Y14150861D01*
X30349006Y14120411D01*
X30502089Y14150861D01*
X30676561Y14306676D01*
X30101280Y14881957D01*
X29525999Y14306676D01*
X27803701Y14306676D01*
X27916403Y14419378D01*
X28278280Y15293025D01*
X28278280Y15518114D01*
X28455851Y15518114D01*
X28486301Y15365031D01*
X28642116Y15190559D01*
X29217397Y15765840D01*
X30985163Y15765840D01*
X31560444Y15190559D01*
X31716259Y15365031D01*
X31746709Y16013566D01*
X31716259Y16166649D01*
X31560444Y16341121D01*
X30985163Y15765840D01*
X29217397Y15765840D01*
X28642116Y16341121D01*
X28486301Y16166649D01*
X28455851Y15518114D01*
X28278280Y15518114D01*
X28278280Y16238655D01*
X27916403Y17112302D01*
X27803701Y17225004D01*
X29525999Y17225004D01*
X30101280Y16649723D01*
X30676561Y17225004D01*
X30502089Y17380819D01*
X29853554Y17411269D01*
X29700471Y17380819D01*
X29525999Y17225004D01*
X27803701Y17225004D01*
X27247742Y17780963D01*
X27042831Y17865840D01*
X27247742Y17950717D01*
X27803701Y18506676D01*
X29525999Y18506676D01*
X29700471Y18350861D01*
X30349006Y18320411D01*
X30502089Y18350861D01*
X30676561Y18506676D01*
X30101280Y19081957D01*
X29525999Y18506676D01*
X27803701Y18506676D01*
X27916403Y18619378D01*
X28278280Y19493025D01*
X28278280Y19718114D01*
X28455851Y19718114D01*
X28486301Y19565031D01*
X28642116Y19390559D01*
X29217397Y19965840D01*
X30985163Y19965840D01*
X31560444Y19390559D01*
X31716259Y19565031D01*
X31746709Y20213566D01*
X31716259Y20366649D01*
X31560444Y20541121D01*
X30985163Y19965840D01*
X29217397Y19965840D01*
X28642116Y20541121D01*
X28486301Y20366649D01*
X28455851Y19718114D01*
X28278280Y19718114D01*
X28278280Y20438655D01*
X27916403Y21312302D01*
X27247742Y21980963D01*
X26374095Y22342840D01*
X25428465Y22342840D01*
X24554818Y21980963D01*
X23886157Y21312302D01*
X23524280Y20438655D01*
X12478280Y20438655D01*
X12116403Y21312302D01*
X11447742Y21980963D01*
X10574095Y22342840D01*
X9628465Y22342840D01*
X8754818Y21980963D01*
X8086157Y21312302D01*
X7724280Y20438655D01*
X7451953Y20438655D01*
X7360444Y20541121D01*
X6785163Y19965840D01*
X5017397Y19965840D01*
X4442116Y20541121D01*
X4286301Y20366649D01*
X4255851Y19718114D01*
X-3796720Y19718114D01*
X-3796720Y25287839D01*
X2774280Y25287839D01*
X2774280Y24043841D01*
X3250337Y22894537D01*
X4129977Y22014897D01*
X5279281Y21538840D01*
X5453466Y21538840D01*
X5325999Y21425004D01*
X5901280Y20849723D01*
X6476561Y21425004D01*
X6349094Y21538840D01*
X6523279Y21538840D01*
X7672583Y22014897D01*
X8552223Y22894537D01*
X9028280Y24043841D01*
X9028280Y25287839D01*
X26974280Y25287839D01*
X26974280Y24043841D01*
X27450337Y22894537D01*
X28329977Y22014897D01*
X29479281Y21538840D01*
X29653466Y21538840D01*
X29525999Y21425004D01*
X30101280Y20849723D01*
X30676561Y21425004D01*
X30549094Y21538840D01*
X30723279Y21538840D01*
X31872583Y22014897D01*
X32752223Y22894537D01*
X33228280Y24043841D01*
X33228280Y25287839D01*
X32752223Y26437143D01*
X31872583Y27316783D01*
X30723279Y27792840D01*
X29479281Y27792840D01*
X28329977Y27316783D01*
X27450337Y26437143D01*
X26974280Y25287839D01*
X9028280Y25287839D01*
X8552223Y26437143D01*
X7672583Y27316783D01*
X6523279Y27792840D01*
X5279281Y27792840D01*
X4129977Y27316783D01*
X3250337Y26437143D01*
X2774280Y25287839D01*
X-3796720Y25287839D01*
X-3796720Y36320439D01*
X2774280Y36320439D01*
X2774280Y35076441D01*
X3250337Y33927137D01*
X4129977Y33047497D01*
X5279281Y32571440D01*
X6523279Y32571440D01*
X7672583Y33047497D01*
X8552223Y33927137D01*
X9028280Y35076441D01*
X9028280Y36320439D01*
X26974280Y36320439D01*
X26974280Y35076441D01*
X27450337Y33927137D01*
X28329977Y33047497D01*
X29479281Y32571440D01*
X30723279Y32571440D01*
X31872583Y33047497D01*
X32752223Y33927137D01*
X33228280Y35076441D01*
X33228280Y36320439D01*
X32752223Y37469743D01*
X31872583Y38349383D01*
X30723279Y38825440D01*
X30549094Y38825440D01*
X30676561Y38939276D01*
X30101280Y39514557D01*
X29525999Y38939276D01*
X29653466Y38825440D01*
X29479281Y38825440D01*
X28329977Y38349383D01*
X27450337Y37469743D01*
X26974280Y36320439D01*
X9028280Y36320439D01*
X8552223Y37469743D01*
X7672583Y38349383D01*
X6523279Y38825440D01*
X6349094Y38825440D01*
X6476561Y38939276D01*
X5901280Y39514557D01*
X5325999Y38939276D01*
X5453466Y38825440D01*
X5279281Y38825440D01*
X4129977Y38349383D01*
X3250337Y37469743D01*
X2774280Y36320439D01*
X-3796720Y36320439D01*
X-3796720Y40150714D01*
X4255851Y40150714D01*
X4286301Y39997631D01*
X4442116Y39823159D01*
X5017397Y40398440D01*
X6785163Y40398440D01*
X7360444Y39823159D01*
X7516259Y39997631D01*
X7546709Y40646166D01*
X7516259Y40799249D01*
X7360444Y40973721D01*
X6785163Y40398440D01*
X5017397Y40398440D01*
X4442116Y40973721D01*
X4286301Y40799249D01*
X4255851Y40150714D01*
X-3796720Y40150714D01*
X-3796720Y41857604D01*
X5325999Y41857604D01*
X5901280Y41282323D01*
X6476561Y41857604D01*
X6302089Y42013419D01*
X5653554Y42043869D01*
X5500471Y42013419D01*
X5325999Y41857604D01*
X-3796720Y41857604D01*
X-3796720Y43139276D01*
X5325999Y43139276D01*
X5500471Y42983461D01*
X6149006Y42953011D01*
X6302089Y42983461D01*
X6476561Y43139276D01*
X5901280Y43714557D01*
X5325999Y43139276D01*
X-3796720Y43139276D01*
X-3796720Y44350714D01*
X4255851Y44350714D01*
X4286301Y44197631D01*
X4442116Y44023159D01*
X5017397Y44598440D01*
X6785163Y44598440D01*
X7360444Y44023159D01*
X7516259Y44197631D01*
X7546709Y44846166D01*
X7516259Y44999249D01*
X7360444Y45173721D01*
X6785163Y44598440D01*
X5017397Y44598440D01*
X4442116Y45173721D01*
X4286301Y44999249D01*
X4255851Y44350714D01*
X-3796720Y44350714D01*
X-3796720Y46057604D01*
X5325999Y46057604D01*
X5901280Y45482323D01*
X6476561Y46057604D01*
X6302089Y46213419D01*
X5653554Y46243869D01*
X5500471Y46213419D01*
X5325999Y46057604D01*
X-3796720Y46057604D01*
X-3796720Y47339276D01*
X5325999Y47339276D01*
X5500471Y47183461D01*
X6149006Y47153011D01*
X6302089Y47183461D01*
X6476561Y47339276D01*
X5901280Y47914557D01*
X5325999Y47339276D01*
X-3796720Y47339276D01*
X-3796720Y48550714D01*
X4255851Y48550714D01*
X4286301Y48397631D01*
X4442116Y48223159D01*
X5017397Y48798440D01*
X6785163Y48798440D01*
X7360444Y48223159D01*
X7516259Y48397631D01*
X7546709Y49046166D01*
X7516259Y49199249D01*
X7451953Y49271255D01*
X7724280Y49271255D01*
X7724280Y48325625D01*
X8086157Y47451978D01*
X8754818Y46783317D01*
X8959729Y46698440D01*
X8754818Y46613563D01*
X8086157Y45944902D01*
X7724280Y45071255D01*
X7724280Y44125625D01*
X8086157Y43251978D01*
X8754818Y42583317D01*
X8959729Y42498440D01*
X8754818Y42413563D01*
X8086157Y41744902D01*
X7724280Y40871255D01*
X7724280Y39925625D01*
X8086157Y39051978D01*
X8754818Y38383317D01*
X9628465Y38021440D01*
X10574095Y38021440D01*
X11447742Y38383317D01*
X12116403Y39051978D01*
X12478280Y39925625D01*
X12478280Y40871255D01*
X12116403Y41744902D01*
X11447742Y42413563D01*
X11242831Y42498440D01*
X11447742Y42583317D01*
X12116403Y43251978D01*
X12478280Y44125625D01*
X12478280Y45071255D01*
X12116403Y45944902D01*
X11447742Y46613563D01*
X11242831Y46698440D01*
X11447742Y46783317D01*
X12116403Y47451978D01*
X12478280Y48325625D01*
X12478280Y49271255D01*
X23524280Y49271255D01*
X23524280Y48325625D01*
X23886157Y47451978D01*
X24554818Y46783317D01*
X24759729Y46698440D01*
X24554818Y46613563D01*
X23886157Y45944902D01*
X23524280Y45071255D01*
X23524280Y44125625D01*
X23886157Y43251978D01*
X24554818Y42583317D01*
X24759729Y42498440D01*
X24554818Y42413563D01*
X23886157Y41744902D01*
X23524280Y40871255D01*
X23524280Y39925625D01*
X23886157Y39051978D01*
X24554818Y38383317D01*
X25428465Y38021440D01*
X26374095Y38021440D01*
X27247742Y38383317D01*
X27916403Y39051978D01*
X28278280Y39925625D01*
X28278280Y40150714D01*
X28455851Y40150714D01*
X28486301Y39997631D01*
X28642116Y39823159D01*
X29217397Y40398440D01*
X30985163Y40398440D01*
X31560444Y39823159D01*
X31716259Y39997631D01*
X31746709Y40646166D01*
X31716259Y40799249D01*
X31560444Y40973721D01*
X30985163Y40398440D01*
X29217397Y40398440D01*
X28642116Y40973721D01*
X28486301Y40799249D01*
X28455851Y40150714D01*
X28278280Y40150714D01*
X28278280Y40871255D01*
X27916403Y41744902D01*
X27803701Y41857604D01*
X29525999Y41857604D01*
X30101280Y41282323D01*
X30676561Y41857604D01*
X30502089Y42013419D01*
X29853554Y42043869D01*
X29700471Y42013419D01*
X29525999Y41857604D01*
X27803701Y41857604D01*
X27247742Y42413563D01*
X27042831Y42498440D01*
X27247742Y42583317D01*
X27803701Y43139276D01*
X29525999Y43139276D01*
X29700471Y42983461D01*
X30349006Y42953011D01*
X30502089Y42983461D01*
X30676561Y43139276D01*
X30101280Y43714557D01*
X29525999Y43139276D01*
X27803701Y43139276D01*
X27916403Y43251978D01*
X28278280Y44125625D01*
X28278280Y44350714D01*
X28455851Y44350714D01*
X28486301Y44197631D01*
X28642116Y44023159D01*
X29217397Y44598440D01*
X30985163Y44598440D01*
X31560444Y44023159D01*
X31716259Y44197631D01*
X31746709Y44846166D01*
X31716259Y44999249D01*
X31560444Y45173721D01*
X30985163Y44598440D01*
X29217397Y44598440D01*
X28642116Y45173721D01*
X28486301Y44999249D01*
X28455851Y44350714D01*
X28278280Y44350714D01*
X28278280Y45071255D01*
X27916403Y45944902D01*
X27803701Y46057604D01*
X29525999Y46057604D01*
X30101280Y45482323D01*
X30676561Y46057604D01*
X30502089Y46213419D01*
X29853554Y46243869D01*
X29700471Y46213419D01*
X29525999Y46057604D01*
X27803701Y46057604D01*
X27247742Y46613563D01*
X27042831Y46698440D01*
X27247742Y46783317D01*
X27803701Y47339276D01*
X29525999Y47339276D01*
X29700471Y47183461D01*
X30349006Y47153011D01*
X30502089Y47183461D01*
X30676561Y47339276D01*
X30101280Y47914557D01*
X29525999Y47339276D01*
X27803701Y47339276D01*
X27916403Y47451978D01*
X28278280Y48325625D01*
X28278280Y48550714D01*
X28455851Y48550714D01*
X28486301Y48397631D01*
X28642116Y48223159D01*
X29217397Y48798440D01*
X30985163Y48798440D01*
X31560444Y48223159D01*
X31716259Y48397631D01*
X31746709Y49046166D01*
X31716259Y49199249D01*
X31560444Y49373721D01*
X30985163Y48798440D01*
X29217397Y48798440D01*
X28642116Y49373721D01*
X28486301Y49199249D01*
X28455851Y48550714D01*
X28278280Y48550714D01*
X28278280Y49271255D01*
X27916403Y50144902D01*
X27247742Y50813563D01*
X26374095Y51175440D01*
X25428465Y51175440D01*
X24554818Y50813563D01*
X23886157Y50144902D01*
X23524280Y49271255D01*
X12478280Y49271255D01*
X12116403Y50144902D01*
X11447742Y50813563D01*
X10574095Y51175440D01*
X9628465Y51175440D01*
X8754818Y50813563D01*
X8086157Y50144902D01*
X7724280Y49271255D01*
X7451953Y49271255D01*
X7360444Y49373721D01*
X6785163Y48798440D01*
X5017397Y48798440D01*
X4442116Y49373721D01*
X4286301Y49199249D01*
X4255851Y48550714D01*
X-3796720Y48550714D01*
X-3796720Y54120439D01*
X2774280Y54120439D01*
X2774280Y52876441D01*
X3250337Y51727137D01*
X4129977Y50847497D01*
X5279281Y50371440D01*
X5453466Y50371440D01*
X5325999Y50257604D01*
X5901280Y49682323D01*
X6476561Y50257604D01*
X6349094Y50371440D01*
X6523279Y50371440D01*
X7672583Y50847497D01*
X8552223Y51727137D01*
X9028280Y52876441D01*
X9028280Y54120439D01*
X26974280Y54120439D01*
X26974280Y52876441D01*
X27450337Y51727137D01*
X28329977Y50847497D01*
X29479281Y50371440D01*
X29653466Y50371440D01*
X29525999Y50257604D01*
X30101280Y49682323D01*
X30676561Y50257604D01*
X30549094Y50371440D01*
X30723279Y50371440D01*
X31872583Y50847497D01*
X32752223Y51727137D01*
X33228280Y52876441D01*
X33228280Y54120439D01*
X32752223Y55269743D01*
X31872583Y56149383D01*
X30723279Y56625440D01*
X29479281Y56625440D01*
X28329977Y56149383D01*
X27450337Y55269743D01*
X26974280Y54120439D01*
X9028280Y54120439D01*
X8552223Y55269743D01*
X7672583Y56149383D01*
X6523279Y56625440D01*
X5279281Y56625440D01*
X4129977Y56149383D01*
X3250337Y55269743D01*
X2774280Y54120439D01*
X-3796720Y54120439D01*
X-3796720Y84320439D01*
X2774280Y84320439D01*
X2774280Y83076441D01*
X3250337Y81927137D01*
X4129977Y81047497D01*
X4595801Y80854546D01*
X4086157Y80344902D01*
X3724280Y79471255D01*
X3724280Y78525625D01*
X4086157Y77651978D01*
X4754818Y76983317D01*
X4959729Y76898440D01*
X4754818Y76813563D01*
X4086157Y76144902D01*
X3724280Y75271255D01*
X3724280Y74325625D01*
X4086157Y73451978D01*
X4754818Y72783317D01*
X4959729Y72698440D01*
X4754818Y72613563D01*
X4086157Y71944902D01*
X3724280Y71071255D01*
X3724280Y70125625D01*
X4086157Y69251978D01*
X4754818Y68583317D01*
X4959729Y68498440D01*
X4754818Y68413563D01*
X4086157Y67744902D01*
X3724280Y66871255D01*
X3724280Y65925625D01*
X4086157Y65051978D01*
X4595801Y64542334D01*
X4129977Y64349383D01*
X3250337Y63469743D01*
X2774280Y62320439D01*
X2774280Y61076441D01*
X3250337Y59927137D01*
X4129977Y59047497D01*
X5279281Y58571440D01*
X6523279Y58571440D01*
X7672583Y59047497D01*
X8552223Y59927137D01*
X9028280Y61076441D01*
X9028280Y62320439D01*
X8552223Y63469743D01*
X7672583Y64349383D01*
X7489601Y64425176D01*
X8003701Y64939276D01*
X9725999Y64939276D01*
X9900471Y64783461D01*
X10549006Y64753011D01*
X10702089Y64783461D01*
X10876561Y64939276D01*
X25125999Y64939276D01*
X25300471Y64783461D01*
X25949006Y64753011D01*
X26102089Y64783461D01*
X26276561Y64939276D01*
X25701280Y65514557D01*
X25125999Y64939276D01*
X10876561Y64939276D01*
X10301280Y65514557D01*
X9725999Y64939276D01*
X8003701Y64939276D01*
X8116403Y65051978D01*
X8478280Y65925625D01*
X8478280Y66150714D01*
X8655851Y66150714D01*
X8686301Y65997631D01*
X8842116Y65823159D01*
X9417397Y66398440D01*
X11185163Y66398440D01*
X11760444Y65823159D01*
X11916259Y65997631D01*
X11923446Y66150714D01*
X24055851Y66150714D01*
X24086301Y65997631D01*
X24242116Y65823159D01*
X24817397Y66398440D01*
X26585163Y66398440D01*
X27160444Y65823159D01*
X27316259Y65997631D01*
X27346709Y66646166D01*
X27316259Y66799249D01*
X27160444Y66973721D01*
X26585163Y66398440D01*
X24817397Y66398440D01*
X24242116Y66973721D01*
X24086301Y66799249D01*
X24055851Y66150714D01*
X11923446Y66150714D01*
X11946709Y66646166D01*
X11916259Y66799249D01*
X11760444Y66973721D01*
X11185163Y66398440D01*
X9417397Y66398440D01*
X8842116Y66973721D01*
X8686301Y66799249D01*
X8655851Y66150714D01*
X8478280Y66150714D01*
X8478280Y66871255D01*
X8116403Y67744902D01*
X8003701Y67857604D01*
X9725999Y67857604D01*
X10301280Y67282323D01*
X10876561Y67857604D01*
X25125999Y67857604D01*
X25701280Y67282323D01*
X26276561Y67857604D01*
X26102089Y68013419D01*
X25453554Y68043869D01*
X25300471Y68013419D01*
X25125999Y67857604D01*
X10876561Y67857604D01*
X10702089Y68013419D01*
X10053554Y68043869D01*
X9900471Y68013419D01*
X9725999Y67857604D01*
X8003701Y67857604D01*
X7447742Y68413563D01*
X7242831Y68498440D01*
X7447742Y68583317D01*
X8003701Y69139276D01*
X9725999Y69139276D01*
X9900471Y68983461D01*
X10549006Y68953011D01*
X10702089Y68983461D01*
X10876561Y69139276D01*
X25125999Y69139276D01*
X25300471Y68983461D01*
X25949006Y68953011D01*
X26102089Y68983461D01*
X26276561Y69139276D01*
X25701280Y69714557D01*
X25125999Y69139276D01*
X10876561Y69139276D01*
X10301280Y69714557D01*
X9725999Y69139276D01*
X8003701Y69139276D01*
X8116403Y69251978D01*
X8478280Y70125625D01*
X8478280Y70350714D01*
X8655851Y70350714D01*
X8686301Y70197631D01*
X8842116Y70023159D01*
X9417397Y70598440D01*
X11185163Y70598440D01*
X11760444Y70023159D01*
X11916259Y70197631D01*
X11923446Y70350714D01*
X24055851Y70350714D01*
X24086301Y70197631D01*
X24242116Y70023159D01*
X24817397Y70598440D01*
X26585163Y70598440D01*
X27160444Y70023159D01*
X27316259Y70197631D01*
X27346709Y70846166D01*
X27316259Y70999249D01*
X27160444Y71173721D01*
X26585163Y70598440D01*
X24817397Y70598440D01*
X24242116Y71173721D01*
X24086301Y70999249D01*
X24055851Y70350714D01*
X11923446Y70350714D01*
X11946709Y70846166D01*
X11916259Y70999249D01*
X11760444Y71173721D01*
X11185163Y70598440D01*
X9417397Y70598440D01*
X8842116Y71173721D01*
X8686301Y70999249D01*
X8655851Y70350714D01*
X8478280Y70350714D01*
X8478280Y71071255D01*
X8116403Y71944902D01*
X8003701Y72057604D01*
X9725999Y72057604D01*
X10301280Y71482323D01*
X10876561Y72057604D01*
X25125999Y72057604D01*
X25701280Y71482323D01*
X26276561Y72057604D01*
X26102089Y72213419D01*
X25453554Y72243869D01*
X25300471Y72213419D01*
X25125999Y72057604D01*
X10876561Y72057604D01*
X10702089Y72213419D01*
X10053554Y72243869D01*
X9900471Y72213419D01*
X9725999Y72057604D01*
X8003701Y72057604D01*
X7447742Y72613563D01*
X7242831Y72698440D01*
X7447742Y72783317D01*
X8003701Y73339276D01*
X9725999Y73339276D01*
X9900471Y73183461D01*
X10549006Y73153011D01*
X10702089Y73183461D01*
X10876561Y73339276D01*
X25125999Y73339276D01*
X25300471Y73183461D01*
X25949006Y73153011D01*
X26102089Y73183461D01*
X26276561Y73339276D01*
X25701280Y73914557D01*
X25125999Y73339276D01*
X10876561Y73339276D01*
X10301280Y73914557D01*
X9725999Y73339276D01*
X8003701Y73339276D01*
X8116403Y73451978D01*
X8478280Y74325625D01*
X8478280Y74550714D01*
X8655851Y74550714D01*
X8686301Y74397631D01*
X8842116Y74223159D01*
X9417397Y74798440D01*
X11185163Y74798440D01*
X11760444Y74223159D01*
X11916259Y74397631D01*
X11923446Y74550714D01*
X24055851Y74550714D01*
X24086301Y74397631D01*
X24242116Y74223159D01*
X24817397Y74798440D01*
X26585163Y74798440D01*
X27160444Y74223159D01*
X27316259Y74397631D01*
X27346709Y75046166D01*
X27316259Y75199249D01*
X27160444Y75373721D01*
X26585163Y74798440D01*
X24817397Y74798440D01*
X24242116Y75373721D01*
X24086301Y75199249D01*
X24055851Y74550714D01*
X11923446Y74550714D01*
X11946709Y75046166D01*
X11916259Y75199249D01*
X11760444Y75373721D01*
X11185163Y74798440D01*
X9417397Y74798440D01*
X8842116Y75373721D01*
X8686301Y75199249D01*
X8655851Y74550714D01*
X8478280Y74550714D01*
X8478280Y75271255D01*
X8116403Y76144902D01*
X8003701Y76257604D01*
X9725999Y76257604D01*
X10301280Y75682323D01*
X10876561Y76257604D01*
X25125999Y76257604D01*
X25701280Y75682323D01*
X26276561Y76257604D01*
X26102089Y76413419D01*
X25453554Y76443869D01*
X25300471Y76413419D01*
X25125999Y76257604D01*
X10876561Y76257604D01*
X10702089Y76413419D01*
X10053554Y76443869D01*
X9900471Y76413419D01*
X9725999Y76257604D01*
X8003701Y76257604D01*
X7447742Y76813563D01*
X7242831Y76898440D01*
X7447742Y76983317D01*
X8003701Y77539276D01*
X9725999Y77539276D01*
X9900471Y77383461D01*
X10549006Y77353011D01*
X10702089Y77383461D01*
X10876561Y77539276D01*
X25125999Y77539276D01*
X25300471Y77383461D01*
X25949006Y77353011D01*
X26102089Y77383461D01*
X26276561Y77539276D01*
X25701280Y78114557D01*
X25125999Y77539276D01*
X10876561Y77539276D01*
X10301280Y78114557D01*
X9725999Y77539276D01*
X8003701Y77539276D01*
X8116403Y77651978D01*
X8478280Y78525625D01*
X8478280Y78750714D01*
X8655851Y78750714D01*
X8686301Y78597631D01*
X8842116Y78423159D01*
X9417397Y78998440D01*
X11185163Y78998440D01*
X11760444Y78423159D01*
X11916259Y78597631D01*
X11923446Y78750714D01*
X24055851Y78750714D01*
X24086301Y78597631D01*
X24242116Y78423159D01*
X24817397Y78998440D01*
X26585163Y78998440D01*
X27160444Y78423159D01*
X27316259Y78597631D01*
X27346709Y79246166D01*
X27316259Y79399249D01*
X27160444Y79573721D01*
X26585163Y78998440D01*
X24817397Y78998440D01*
X24242116Y79573721D01*
X24086301Y79399249D01*
X24055851Y78750714D01*
X11923446Y78750714D01*
X11946709Y79246166D01*
X11916259Y79399249D01*
X11760444Y79573721D01*
X11185163Y78998440D01*
X9417397Y78998440D01*
X8842116Y79573721D01*
X8686301Y79399249D01*
X8655851Y78750714D01*
X8478280Y78750714D01*
X8478280Y79471255D01*
X8116403Y80344902D01*
X8003701Y80457604D01*
X9725999Y80457604D01*
X10301280Y79882323D01*
X10876561Y80457604D01*
X25125999Y80457604D01*
X25701280Y79882323D01*
X26276561Y80457604D01*
X26102089Y80613419D01*
X25453554Y80643869D01*
X25300471Y80613419D01*
X25125999Y80457604D01*
X10876561Y80457604D01*
X10702089Y80613419D01*
X10053554Y80643869D01*
X9900471Y80613419D01*
X9725999Y80457604D01*
X8003701Y80457604D01*
X7489601Y80971704D01*
X7672583Y81047497D01*
X8552223Y81927137D01*
X9028280Y83076441D01*
X9028280Y84320439D01*
X26974280Y84320439D01*
X26974280Y83076441D01*
X27450337Y81927137D01*
X28329977Y81047497D01*
X28512959Y80971704D01*
X27886157Y80344902D01*
X27524280Y79471255D01*
X27524280Y78525625D01*
X27886157Y77651978D01*
X28554818Y76983317D01*
X28759729Y76898440D01*
X28554818Y76813563D01*
X27886157Y76144902D01*
X27524280Y75271255D01*
X27524280Y74325625D01*
X27886157Y73451978D01*
X28554818Y72783317D01*
X28759729Y72698440D01*
X28554818Y72613563D01*
X27886157Y71944902D01*
X27524280Y71071255D01*
X27524280Y70125625D01*
X27886157Y69251978D01*
X28554818Y68583317D01*
X28759729Y68498440D01*
X28554818Y68413563D01*
X27886157Y67744902D01*
X27524280Y66871255D01*
X27524280Y65925625D01*
X27886157Y65051978D01*
X28512959Y64425176D01*
X28329977Y64349383D01*
X27450337Y63469743D01*
X26974280Y62320439D01*
X26974280Y61076441D01*
X27450337Y59927137D01*
X28329977Y59047497D01*
X29479281Y58571440D01*
X30723279Y58571440D01*
X31872583Y59047497D01*
X32752223Y59927137D01*
X33228280Y61076441D01*
X33228280Y62320439D01*
X32752223Y63469743D01*
X31872583Y64349383D01*
X31406759Y64542334D01*
X31916403Y65051978D01*
X32278280Y65925625D01*
X32278280Y66871255D01*
X31916403Y67744902D01*
X31247742Y68413563D01*
X31042831Y68498440D01*
X31247742Y68583317D01*
X31916403Y69251978D01*
X32278280Y70125625D01*
X32278280Y71071255D01*
X31916403Y71944902D01*
X31247742Y72613563D01*
X31042831Y72698440D01*
X31247742Y72783317D01*
X31916403Y73451978D01*
X32278280Y74325625D01*
X32278280Y75271255D01*
X31916403Y76144902D01*
X31247742Y76813563D01*
X31042831Y76898440D01*
X31247742Y76983317D01*
X31916403Y77651978D01*
X32278280Y78525625D01*
X32278280Y79471255D01*
X31916403Y80344902D01*
X31406759Y80854546D01*
X31872583Y81047497D01*
X32752223Y81927137D01*
X32939158Y82378440D01*
X38914280Y82378440D01*
X38914280Y75108440D01*
X38923947Y75059839D01*
X38951477Y75018637D01*
X38992679Y74991107D01*
X39034280Y74982832D01*
X39034280Y268440D01*
X39044281Y219042D01*
X39072090Y178029D01*
X41292090Y-2011971D01*
X41332679Y-2038893D01*
X41381280Y-2048560D01*
X68881280Y-2048560D01*
X68929613Y-2039003D01*
X68970878Y-2011567D01*
X71170878Y178433D01*
X71198613Y219839D01*
X71208280Y268440D01*
X71208280Y550286D01*
X137115102Y550286D01*
X137115102Y-553406D01*
X137311859Y-923214D01*
X138233513Y-1560D01*
X141769047Y-1560D01*
X142690701Y-923214D01*
X142887458Y-553406D01*
X142887458Y550286D01*
X142690701Y920094D01*
X141769047Y-1560D01*
X138233513Y-1560D01*
X137311859Y920094D01*
X137115102Y550286D01*
X71208280Y550286D01*
X71208280Y2687861D01*
X139079626Y2687861D01*
X140001280Y1766207D01*
X140922934Y2687861D01*
X140553126Y2884618D01*
X139449434Y2884618D01*
X139079626Y2687861D01*
X71208280Y2687861D01*
X71208280Y5647261D01*
X112703401Y5647261D01*
X113857205Y5293875D01*
X116145355Y5293875D01*
X117299159Y5647261D01*
X115001280Y7945139D01*
X112703401Y5647261D01*
X71208280Y5647261D01*
X71208280Y14392515D01*
X107046715Y14392515D01*
X107046715Y12104365D01*
X107400101Y10950561D01*
X109697979Y13248440D01*
X120304581Y13248440D01*
X122602459Y10950561D01*
X122955845Y12104365D01*
X122955845Y14392515D01*
X122602459Y15546319D01*
X120304581Y13248440D01*
X109697979Y13248440D01*
X107400101Y15546319D01*
X107046715Y14392515D01*
X71208280Y14392515D01*
X71208280Y20849619D01*
X112703401Y20849619D01*
X115001280Y18551741D01*
X117299159Y20849619D01*
X116145355Y21203005D01*
X113857205Y21203005D01*
X112703401Y20849619D01*
X71208280Y20849619D01*
X71208280Y28147261D01*
X112703401Y28147261D01*
X113857205Y27793875D01*
X116145355Y27793875D01*
X117299159Y28147261D01*
X115001280Y30445139D01*
X112703401Y28147261D01*
X71208280Y28147261D01*
X71208280Y36892515D01*
X107046715Y36892515D01*
X107046715Y34604365D01*
X107400101Y33450561D01*
X109697979Y35748440D01*
X120304581Y35748440D01*
X122602459Y33450561D01*
X122955845Y34604365D01*
X122955845Y36892515D01*
X122602459Y38046319D01*
X120304581Y35748440D01*
X109697979Y35748440D01*
X107400101Y38046319D01*
X107046715Y36892515D01*
X71208280Y36892515D01*
X71208280Y43349619D01*
X112703401Y43349619D01*
X115001280Y41051741D01*
X117299159Y43349619D01*
X116145355Y43703005D01*
X113857205Y43703005D01*
X112703401Y43349619D01*
X71208280Y43349619D01*
X71208280Y50647261D01*
X112703401Y50647261D01*
X113857205Y50293875D01*
X116145355Y50293875D01*
X117299159Y50647261D01*
X115001280Y52945139D01*
X112703401Y50647261D01*
X71208280Y50647261D01*
X71208280Y59392515D01*
X107046715Y59392515D01*
X107046715Y57104365D01*
X107400101Y55950561D01*
X109697979Y58248440D01*
X120304581Y58248440D01*
X122602459Y55950561D01*
X122955845Y57104365D01*
X122955845Y59392515D01*
X122602459Y60546319D01*
X120304581Y58248440D01*
X109697979Y58248440D01*
X107400101Y60546319D01*
X107046715Y59392515D01*
X71208280Y59392515D01*
X71208280Y65849619D01*
X112703401Y65849619D01*
X115001280Y63551741D01*
X117299159Y65849619D01*
X116145355Y66203005D01*
X113857205Y66203005D01*
X112703401Y65849619D01*
X71208280Y65849619D01*
X71208280Y73147261D01*
X112703401Y73147261D01*
X113857205Y72793875D01*
X116145355Y72793875D01*
X117299159Y73147261D01*
X115001280Y75445139D01*
X112703401Y73147261D01*
X71208280Y73147261D01*
X71208280Y81892515D01*
X107046715Y81892515D01*
X107046715Y79604365D01*
X107400101Y78450561D01*
X109697979Y80748440D01*
X120304581Y80748440D01*
X122602459Y78450561D01*
X122955845Y79604365D01*
X122955845Y81892515D01*
X122602459Y83046319D01*
X120304581Y80748440D01*
X109697979Y80748440D01*
X107400101Y83046319D01*
X107046715Y81892515D01*
X71208280Y81892515D01*
X71208280Y82408440D01*
X71199266Y82455434D01*
X71172301Y82497007D01*
X65477442Y88349619D01*
X112703401Y88349619D01*
X115001280Y86051741D01*
X116258558Y87309019D01*
X139079626Y87309019D01*
X139449434Y87112262D01*
X140553126Y87112262D01*
X140922934Y87309019D01*
X140001280Y88230673D01*
X139079626Y87309019D01*
X116258558Y87309019D01*
X117299159Y88349619D01*
X116145355Y88703005D01*
X113857205Y88703005D01*
X112703401Y88349619D01*
X65477442Y88349619D01*
X63952301Y89917007D01*
X63909613Y89945883D01*
X63860991Y89955440D01*
X46310991Y89915440D01*
X46261417Y89905242D01*
X46220514Y89877269D01*
X39801018Y83317784D01*
X38951477Y82468243D01*
X38923947Y82427041D01*
X38914280Y82378440D01*
X32939158Y82378440D01*
X33228280Y83076441D01*
X33228280Y84320439D01*
X32752223Y85469743D01*
X31872583Y86349383D01*
X30723279Y86825440D01*
X29479281Y86825440D01*
X28329977Y86349383D01*
X27450337Y85469743D01*
X26974280Y84320439D01*
X9028280Y84320439D01*
X8552223Y85469743D01*
X7672583Y86349383D01*
X6523279Y86825440D01*
X5279281Y86825440D01*
X4129977Y86349383D01*
X3250337Y85469743D01*
X2774280Y84320439D01*
X-3796720Y84320439D01*
X-3796720Y87309019D01*
X-920374Y87309019D01*
X-550566Y87112262D01*
X553126Y87112262D01*
X922934Y87309019D01*
X1280Y88230673D01*
X-920374Y87309019D01*
X-3796720Y87309019D01*
X-3796720Y90550286D01*
X-2884898Y90550286D01*
X-2884898Y89446594D01*
X-2688141Y89076786D01*
X-1766487Y89998440D01*
X1769047Y89998440D01*
X2690701Y89076786D01*
X2887458Y89446594D01*
X2887458Y90550286D01*
X137115102Y90550286D01*
X137115102Y89446594D01*
X137311859Y89076786D01*
X138233513Y89998440D01*
X141769047Y89998440D01*
X142690701Y89076786D01*
X142887458Y89446594D01*
X142887458Y90550286D01*
X142690701Y90920094D01*
X141769047Y89998440D01*
X138233513Y89998440D01*
X137311859Y90920094D01*
X137115102Y90550286D01*
X2887458Y90550286D01*
X2690701Y90920094D01*
X1769047Y89998440D01*
X-1766487Y89998440D01*
X-2688141Y90920094D01*
X-2884898Y90550286D01*
X-3796720Y90550286D01*
X-3796720Y92500556D01*
X-3609415Y92687861D01*
X-920374Y92687861D01*
X1280Y91766207D01*
X922934Y92687861D01*
X139079626Y92687861D01*
X140001280Y91766207D01*
X140922934Y92687861D01*
X140553126Y92884618D01*
X139449434Y92884618D01*
X139079626Y92687861D01*
X922934Y92687861D01*
X553126Y92884618D01*
X-550566Y92884618D01*
X-920374Y92687861D01*
X-3609415Y92687861D01*
X-2500835Y93796440D01*
X142503396Y93796440D01*
X143799280Y92500555D01*
X143799280Y92500555D01*
G37*
X143799280Y92500555D02*
X143799281Y-2503674D01*
X142503396Y-3799560D01*
X-2500835Y-3799560D01*
X-3609414Y-2690981D01*
X-920374Y-2690981D01*
X-550566Y-2887738D01*
X553126Y-2887738D01*
X922934Y-2690981D01*
X139079626Y-2690981D01*
X139449434Y-2887738D01*
X140553126Y-2887738D01*
X140922934Y-2690981D01*
X140001280Y-1769327D01*
X139079626Y-2690981D01*
X922934Y-2690981D01*
X1280Y-1769327D01*
X-920374Y-2690981D01*
X-3609414Y-2690981D01*
X-3796720Y-2503676D01*
X-3796720Y550286D01*
X-2884898Y550286D01*
X-2884898Y-553406D01*
X-2688141Y-923214D01*
X-1766487Y-1560D01*
X1769047Y-1560D01*
X2690701Y-923214D01*
X2887458Y-553406D01*
X2887458Y550286D01*
X2690701Y920094D01*
X1769047Y-1560D01*
X-1766487Y-1560D01*
X-2688141Y920094D01*
X-2884898Y550286D01*
X-3796720Y550286D01*
X-3796720Y2687861D01*
X-920374Y2687861D01*
X1280Y1766207D01*
X922934Y2687861D01*
X553126Y2884618D01*
X-550566Y2884618D01*
X-920374Y2687861D01*
X-3796720Y2687861D01*
X-3796720Y7487839D01*
X2774280Y7487839D01*
X2774280Y6243841D01*
X3250337Y5094537D01*
X4129977Y4214897D01*
X5279281Y3738840D01*
X6523279Y3738840D01*
X7672583Y4214897D01*
X8552223Y5094537D01*
X9028280Y6243841D01*
X9028280Y7487839D01*
X26974280Y7487839D01*
X26974280Y6243841D01*
X27450337Y5094537D01*
X28329977Y4214897D01*
X29479281Y3738840D01*
X30723279Y3738840D01*
X31872583Y4214897D01*
X32752223Y5094537D01*
X33228280Y6243841D01*
X33228280Y7487839D01*
X32752223Y8637143D01*
X31872583Y9516783D01*
X30723279Y9992840D01*
X30549094Y9992840D01*
X30676561Y10106676D01*
X30101280Y10681957D01*
X29525999Y10106676D01*
X29653466Y9992840D01*
X29479281Y9992840D01*
X28329977Y9516783D01*
X27450337Y8637143D01*
X26974280Y7487839D01*
X9028280Y7487839D01*
X8552223Y8637143D01*
X7672583Y9516783D01*
X6523279Y9992840D01*
X6349094Y9992840D01*
X6476561Y10106676D01*
X5901280Y10681957D01*
X5325999Y10106676D01*
X5453466Y9992840D01*
X5279281Y9992840D01*
X4129977Y9516783D01*
X3250337Y8637143D01*
X2774280Y7487839D01*
X-3796720Y7487839D01*
X-3796720Y11318114D01*
X4255851Y11318114D01*
X4286301Y11165031D01*
X4442116Y10990559D01*
X5017397Y11565840D01*
X6785163Y11565840D01*
X7360444Y10990559D01*
X7516259Y11165031D01*
X7546709Y11813566D01*
X7516259Y11966649D01*
X7360444Y12141121D01*
X6785163Y11565840D01*
X5017397Y11565840D01*
X4442116Y12141121D01*
X4286301Y11966649D01*
X4255851Y11318114D01*
X-3796720Y11318114D01*
X-3796720Y13025004D01*
X5325999Y13025004D01*
X5901280Y12449723D01*
X6476561Y13025004D01*
X6302089Y13180819D01*
X5653554Y13211269D01*
X5500471Y13180819D01*
X5325999Y13025004D01*
X-3796720Y13025004D01*
X-3796720Y14306676D01*
X5325999Y14306676D01*
X5500471Y14150861D01*
X6149006Y14120411D01*
X6302089Y14150861D01*
X6476561Y14306676D01*
X5901280Y14881957D01*
X5325999Y14306676D01*
X-3796720Y14306676D01*
X-3796720Y15518114D01*
X4255851Y15518114D01*
X4286301Y15365031D01*
X4442116Y15190559D01*
X5017397Y15765840D01*
X6785163Y15765840D01*
X7360444Y15190559D01*
X7516259Y15365031D01*
X7546709Y16013566D01*
X7516259Y16166649D01*
X7360444Y16341121D01*
X6785163Y15765840D01*
X5017397Y15765840D01*
X4442116Y16341121D01*
X4286301Y16166649D01*
X4255851Y15518114D01*
X-3796720Y15518114D01*
X-3796720Y17225004D01*
X5325999Y17225004D01*
X5901280Y16649723D01*
X6476561Y17225004D01*
X6302089Y17380819D01*
X5653554Y17411269D01*
X5500471Y17380819D01*
X5325999Y17225004D01*
X-3796720Y17225004D01*
X-3796720Y18506676D01*
X5325999Y18506676D01*
X5500471Y18350861D01*
X6149006Y18320411D01*
X6302089Y18350861D01*
X6476561Y18506676D01*
X5901280Y19081957D01*
X5325999Y18506676D01*
X-3796720Y18506676D01*
X-3796720Y19718114D01*
X4255851Y19718114D01*
X4286301Y19565031D01*
X4442116Y19390559D01*
X5017397Y19965840D01*
X6785163Y19965840D01*
X7360444Y19390559D01*
X7516259Y19565031D01*
X7546709Y20213566D01*
X7516259Y20366649D01*
X7451953Y20438655D01*
X7724280Y20438655D01*
X7724280Y19493025D01*
X8086157Y18619378D01*
X8754818Y17950717D01*
X8959729Y17865840D01*
X8754818Y17780963D01*
X8086157Y17112302D01*
X7724280Y16238655D01*
X7724280Y15293025D01*
X8086157Y14419378D01*
X8754818Y13750717D01*
X8959729Y13665840D01*
X8754818Y13580963D01*
X8086157Y12912302D01*
X7724280Y12038655D01*
X7724280Y11093025D01*
X8086157Y10219378D01*
X8754818Y9550717D01*
X9628465Y9188840D01*
X10574095Y9188840D01*
X11447742Y9550717D01*
X12116403Y10219378D01*
X12478280Y11093025D01*
X12478280Y12038655D01*
X12116403Y12912302D01*
X11447742Y13580963D01*
X11242831Y13665840D01*
X11447742Y13750717D01*
X12116403Y14419378D01*
X12478280Y15293025D01*
X12478280Y16238655D01*
X12116403Y17112302D01*
X11447742Y17780963D01*
X11242831Y17865840D01*
X11447742Y17950717D01*
X12116403Y18619378D01*
X12478280Y19493025D01*
X12478280Y20438655D01*
X23524280Y20438655D01*
X23524280Y19493025D01*
X23886157Y18619378D01*
X24554818Y17950717D01*
X24759729Y17865840D01*
X24554818Y17780963D01*
X23886157Y17112302D01*
X23524280Y16238655D01*
X23524280Y15293025D01*
X23886157Y14419378D01*
X24554818Y13750717D01*
X24759729Y13665840D01*
X24554818Y13580963D01*
X23886157Y12912302D01*
X23524280Y12038655D01*
X23524280Y11093025D01*
X23886157Y10219378D01*
X24554818Y9550717D01*
X25428465Y9188840D01*
X26374095Y9188840D01*
X27247742Y9550717D01*
X27916403Y10219378D01*
X28278280Y11093025D01*
X28278280Y11318114D01*
X28455851Y11318114D01*
X28486301Y11165031D01*
X28642116Y10990559D01*
X29217397Y11565840D01*
X30985163Y11565840D01*
X31560444Y10990559D01*
X31716259Y11165031D01*
X31746709Y11813566D01*
X31716259Y11966649D01*
X31560444Y12141121D01*
X30985163Y11565840D01*
X29217397Y11565840D01*
X28642116Y12141121D01*
X28486301Y11966649D01*
X28455851Y11318114D01*
X28278280Y11318114D01*
X28278280Y12038655D01*
X27916403Y12912302D01*
X27803701Y13025004D01*
X29525999Y13025004D01*
X30101280Y12449723D01*
X30676561Y13025004D01*
X30502089Y13180819D01*
X29853554Y13211269D01*
X29700471Y13180819D01*
X29525999Y13025004D01*
X27803701Y13025004D01*
X27247742Y13580963D01*
X27042831Y13665840D01*
X27247742Y13750717D01*
X27803701Y14306676D01*
X29525999Y14306676D01*
X29700471Y14150861D01*
X30349006Y14120411D01*
X30502089Y14150861D01*
X30676561Y14306676D01*
X30101280Y14881957D01*
X29525999Y14306676D01*
X27803701Y14306676D01*
X27916403Y14419378D01*
X28278280Y15293025D01*
X28278280Y15518114D01*
X28455851Y15518114D01*
X28486301Y15365031D01*
X28642116Y15190559D01*
X29217397Y15765840D01*
X30985163Y15765840D01*
X31560444Y15190559D01*
X31716259Y15365031D01*
X31746709Y16013566D01*
X31716259Y16166649D01*
X31560444Y16341121D01*
X30985163Y15765840D01*
X29217397Y15765840D01*
X28642116Y16341121D01*
X28486301Y16166649D01*
X28455851Y15518114D01*
X28278280Y15518114D01*
X28278280Y16238655D01*
X27916403Y17112302D01*
X27803701Y17225004D01*
X29525999Y17225004D01*
X30101280Y16649723D01*
X30676561Y17225004D01*
X30502089Y17380819D01*
X29853554Y17411269D01*
X29700471Y17380819D01*
X29525999Y17225004D01*
X27803701Y17225004D01*
X27247742Y17780963D01*
X27042831Y17865840D01*
X27247742Y17950717D01*
X27803701Y18506676D01*
X29525999Y18506676D01*
X29700471Y18350861D01*
X30349006Y18320411D01*
X30502089Y18350861D01*
X30676561Y18506676D01*
X30101280Y19081957D01*
X29525999Y18506676D01*
X27803701Y18506676D01*
X27916403Y18619378D01*
X28278280Y19493025D01*
X28278280Y19718114D01*
X28455851Y19718114D01*
X28486301Y19565031D01*
X28642116Y19390559D01*
X29217397Y19965840D01*
X30985163Y19965840D01*
X31560444Y19390559D01*
X31716259Y19565031D01*
X31746709Y20213566D01*
X31716259Y20366649D01*
X31560444Y20541121D01*
X30985163Y19965840D01*
X29217397Y19965840D01*
X28642116Y20541121D01*
X28486301Y20366649D01*
X28455851Y19718114D01*
X28278280Y19718114D01*
X28278280Y20438655D01*
X27916403Y21312302D01*
X27247742Y21980963D01*
X26374095Y22342840D01*
X25428465Y22342840D01*
X24554818Y21980963D01*
X23886157Y21312302D01*
X23524280Y20438655D01*
X12478280Y20438655D01*
X12116403Y21312302D01*
X11447742Y21980963D01*
X10574095Y22342840D01*
X9628465Y22342840D01*
X8754818Y21980963D01*
X8086157Y21312302D01*
X7724280Y20438655D01*
X7451953Y20438655D01*
X7360444Y20541121D01*
X6785163Y19965840D01*
X5017397Y19965840D01*
X4442116Y20541121D01*
X4286301Y20366649D01*
X4255851Y19718114D01*
X-3796720Y19718114D01*
X-3796720Y25287839D01*
X2774280Y25287839D01*
X2774280Y24043841D01*
X3250337Y22894537D01*
X4129977Y22014897D01*
X5279281Y21538840D01*
X5453466Y21538840D01*
X5325999Y21425004D01*
X5901280Y20849723D01*
X6476561Y21425004D01*
X6349094Y21538840D01*
X6523279Y21538840D01*
X7672583Y22014897D01*
X8552223Y22894537D01*
X9028280Y24043841D01*
X9028280Y25287839D01*
X26974280Y25287839D01*
X26974280Y24043841D01*
X27450337Y22894537D01*
X28329977Y22014897D01*
X29479281Y21538840D01*
X29653466Y21538840D01*
X29525999Y21425004D01*
X30101280Y20849723D01*
X30676561Y21425004D01*
X30549094Y21538840D01*
X30723279Y21538840D01*
X31872583Y22014897D01*
X32752223Y22894537D01*
X33228280Y24043841D01*
X33228280Y25287839D01*
X32752223Y26437143D01*
X31872583Y27316783D01*
X30723279Y27792840D01*
X29479281Y27792840D01*
X28329977Y27316783D01*
X27450337Y26437143D01*
X26974280Y25287839D01*
X9028280Y25287839D01*
X8552223Y26437143D01*
X7672583Y27316783D01*
X6523279Y27792840D01*
X5279281Y27792840D01*
X4129977Y27316783D01*
X3250337Y26437143D01*
X2774280Y25287839D01*
X-3796720Y25287839D01*
X-3796720Y36320439D01*
X2774280Y36320439D01*
X2774280Y35076441D01*
X3250337Y33927137D01*
X4129977Y33047497D01*
X5279281Y32571440D01*
X6523279Y32571440D01*
X7672583Y33047497D01*
X8552223Y33927137D01*
X9028280Y35076441D01*
X9028280Y36320439D01*
X26974280Y36320439D01*
X26974280Y35076441D01*
X27450337Y33927137D01*
X28329977Y33047497D01*
X29479281Y32571440D01*
X30723279Y32571440D01*
X31872583Y33047497D01*
X32752223Y33927137D01*
X33228280Y35076441D01*
X33228280Y36320439D01*
X32752223Y37469743D01*
X31872583Y38349383D01*
X30723279Y38825440D01*
X30549094Y38825440D01*
X30676561Y38939276D01*
X30101280Y39514557D01*
X29525999Y38939276D01*
X29653466Y38825440D01*
X29479281Y38825440D01*
X28329977Y38349383D01*
X27450337Y37469743D01*
X26974280Y36320439D01*
X9028280Y36320439D01*
X8552223Y37469743D01*
X7672583Y38349383D01*
X6523279Y38825440D01*
X6349094Y38825440D01*
X6476561Y38939276D01*
X5901280Y39514557D01*
X5325999Y38939276D01*
X5453466Y38825440D01*
X5279281Y38825440D01*
X4129977Y38349383D01*
X3250337Y37469743D01*
X2774280Y36320439D01*
X-3796720Y36320439D01*
X-3796720Y40150714D01*
X4255851Y40150714D01*
X4286301Y39997631D01*
X4442116Y39823159D01*
X5017397Y40398440D01*
X6785163Y40398440D01*
X7360444Y39823159D01*
X7516259Y39997631D01*
X7546709Y40646166D01*
X7516259Y40799249D01*
X7360444Y40973721D01*
X6785163Y40398440D01*
X5017397Y40398440D01*
X4442116Y40973721D01*
X4286301Y40799249D01*
X4255851Y40150714D01*
X-3796720Y40150714D01*
X-3796720Y41857604D01*
X5325999Y41857604D01*
X5901280Y41282323D01*
X6476561Y41857604D01*
X6302089Y42013419D01*
X5653554Y42043869D01*
X5500471Y42013419D01*
X5325999Y41857604D01*
X-3796720Y41857604D01*
X-3796720Y43139276D01*
X5325999Y43139276D01*
X5500471Y42983461D01*
X6149006Y42953011D01*
X6302089Y42983461D01*
X6476561Y43139276D01*
X5901280Y43714557D01*
X5325999Y43139276D01*
X-3796720Y43139276D01*
X-3796720Y44350714D01*
X4255851Y44350714D01*
X4286301Y44197631D01*
X4442116Y44023159D01*
X5017397Y44598440D01*
X6785163Y44598440D01*
X7360444Y44023159D01*
X7516259Y44197631D01*
X7546709Y44846166D01*
X7516259Y44999249D01*
X7360444Y45173721D01*
X6785163Y44598440D01*
X5017397Y44598440D01*
X4442116Y45173721D01*
X4286301Y44999249D01*
X4255851Y44350714D01*
X-3796720Y44350714D01*
X-3796720Y46057604D01*
X5325999Y46057604D01*
X5901280Y45482323D01*
X6476561Y46057604D01*
X6302089Y46213419D01*
X5653554Y46243869D01*
X5500471Y46213419D01*
X5325999Y46057604D01*
X-3796720Y46057604D01*
X-3796720Y47339276D01*
X5325999Y47339276D01*
X5500471Y47183461D01*
X6149006Y47153011D01*
X6302089Y47183461D01*
X6476561Y47339276D01*
X5901280Y47914557D01*
X5325999Y47339276D01*
X-3796720Y47339276D01*
X-3796720Y48550714D01*
X4255851Y48550714D01*
X4286301Y48397631D01*
X4442116Y48223159D01*
X5017397Y48798440D01*
X6785163Y48798440D01*
X7360444Y48223159D01*
X7516259Y48397631D01*
X7546709Y49046166D01*
X7516259Y49199249D01*
X7451953Y49271255D01*
X7724280Y49271255D01*
X7724280Y48325625D01*
X8086157Y47451978D01*
X8754818Y46783317D01*
X8959729Y46698440D01*
X8754818Y46613563D01*
X8086157Y45944902D01*
X7724280Y45071255D01*
X7724280Y44125625D01*
X8086157Y43251978D01*
X8754818Y42583317D01*
X8959729Y42498440D01*
X8754818Y42413563D01*
X8086157Y41744902D01*
X7724280Y40871255D01*
X7724280Y39925625D01*
X8086157Y39051978D01*
X8754818Y38383317D01*
X9628465Y38021440D01*
X10574095Y38021440D01*
X11447742Y38383317D01*
X12116403Y39051978D01*
X12478280Y39925625D01*
X12478280Y40871255D01*
X12116403Y41744902D01*
X11447742Y42413563D01*
X11242831Y42498440D01*
X11447742Y42583317D01*
X12116403Y43251978D01*
X12478280Y44125625D01*
X12478280Y45071255D01*
X12116403Y45944902D01*
X11447742Y46613563D01*
X11242831Y46698440D01*
X11447742Y46783317D01*
X12116403Y47451978D01*
X12478280Y48325625D01*
X12478280Y49271255D01*
X23524280Y49271255D01*
X23524280Y48325625D01*
X23886157Y47451978D01*
X24554818Y46783317D01*
X24759729Y46698440D01*
X24554818Y46613563D01*
X23886157Y45944902D01*
X23524280Y45071255D01*
X23524280Y44125625D01*
X23886157Y43251978D01*
X24554818Y42583317D01*
X24759729Y42498440D01*
X24554818Y42413563D01*
X23886157Y41744902D01*
X23524280Y40871255D01*
X23524280Y39925625D01*
X23886157Y39051978D01*
X24554818Y38383317D01*
X25428465Y38021440D01*
X26374095Y38021440D01*
X27247742Y38383317D01*
X27916403Y39051978D01*
X28278280Y39925625D01*
X28278280Y40150714D01*
X28455851Y40150714D01*
X28486301Y39997631D01*
X28642116Y39823159D01*
X29217397Y40398440D01*
X30985163Y40398440D01*
X31560444Y39823159D01*
X31716259Y39997631D01*
X31746709Y40646166D01*
X31716259Y40799249D01*
X31560444Y40973721D01*
X30985163Y40398440D01*
X29217397Y40398440D01*
X28642116Y40973721D01*
X28486301Y40799249D01*
X28455851Y40150714D01*
X28278280Y40150714D01*
X28278280Y40871255D01*
X27916403Y41744902D01*
X27803701Y41857604D01*
X29525999Y41857604D01*
X30101280Y41282323D01*
X30676561Y41857604D01*
X30502089Y42013419D01*
X29853554Y42043869D01*
X29700471Y42013419D01*
X29525999Y41857604D01*
X27803701Y41857604D01*
X27247742Y42413563D01*
X27042831Y42498440D01*
X27247742Y42583317D01*
X27803701Y43139276D01*
X29525999Y43139276D01*
X29700471Y42983461D01*
X30349006Y42953011D01*
X30502089Y42983461D01*
X30676561Y43139276D01*
X30101280Y43714557D01*
X29525999Y43139276D01*
X27803701Y43139276D01*
X27916403Y43251978D01*
X28278280Y44125625D01*
X28278280Y44350714D01*
X28455851Y44350714D01*
X28486301Y44197631D01*
X28642116Y44023159D01*
X29217397Y44598440D01*
X30985163Y44598440D01*
X31560444Y44023159D01*
X31716259Y44197631D01*
X31746709Y44846166D01*
X31716259Y44999249D01*
X31560444Y45173721D01*
X30985163Y44598440D01*
X29217397Y44598440D01*
X28642116Y45173721D01*
X28486301Y44999249D01*
X28455851Y44350714D01*
X28278280Y44350714D01*
X28278280Y45071255D01*
X27916403Y45944902D01*
X27803701Y46057604D01*
X29525999Y46057604D01*
X30101280Y45482323D01*
X30676561Y46057604D01*
X30502089Y46213419D01*
X29853554Y46243869D01*
X29700471Y46213419D01*
X29525999Y46057604D01*
X27803701Y46057604D01*
X27247742Y46613563D01*
X27042831Y46698440D01*
X27247742Y46783317D01*
X27803701Y47339276D01*
X29525999Y47339276D01*
X29700471Y47183461D01*
X30349006Y47153011D01*
X30502089Y47183461D01*
X30676561Y47339276D01*
X30101280Y47914557D01*
X29525999Y47339276D01*
X27803701Y47339276D01*
X27916403Y47451978D01*
X28278280Y48325625D01*
X28278280Y48550714D01*
X28455851Y48550714D01*
X28486301Y48397631D01*
X28642116Y48223159D01*
X29217397Y48798440D01*
X30985163Y48798440D01*
X31560444Y48223159D01*
X31716259Y48397631D01*
X31746709Y49046166D01*
X31716259Y49199249D01*
X31560444Y49373721D01*
X30985163Y48798440D01*
X29217397Y48798440D01*
X28642116Y49373721D01*
X28486301Y49199249D01*
X28455851Y48550714D01*
X28278280Y48550714D01*
X28278280Y49271255D01*
X27916403Y50144902D01*
X27247742Y50813563D01*
X26374095Y51175440D01*
X25428465Y51175440D01*
X24554818Y50813563D01*
X23886157Y50144902D01*
X23524280Y49271255D01*
X12478280Y49271255D01*
X12116403Y50144902D01*
X11447742Y50813563D01*
X10574095Y51175440D01*
X9628465Y51175440D01*
X8754818Y50813563D01*
X8086157Y50144902D01*
X7724280Y49271255D01*
X7451953Y49271255D01*
X7360444Y49373721D01*
X6785163Y48798440D01*
X5017397Y48798440D01*
X4442116Y49373721D01*
X4286301Y49199249D01*
X4255851Y48550714D01*
X-3796720Y48550714D01*
X-3796720Y54120439D01*
X2774280Y54120439D01*
X2774280Y52876441D01*
X3250337Y51727137D01*
X4129977Y50847497D01*
X5279281Y50371440D01*
X5453466Y50371440D01*
X5325999Y50257604D01*
X5901280Y49682323D01*
X6476561Y50257604D01*
X6349094Y50371440D01*
X6523279Y50371440D01*
X7672583Y50847497D01*
X8552223Y51727137D01*
X9028280Y52876441D01*
X9028280Y54120439D01*
X26974280Y54120439D01*
X26974280Y52876441D01*
X27450337Y51727137D01*
X28329977Y50847497D01*
X29479281Y50371440D01*
X29653466Y50371440D01*
X29525999Y50257604D01*
X30101280Y49682323D01*
X30676561Y50257604D01*
X30549094Y50371440D01*
X30723279Y50371440D01*
X31872583Y50847497D01*
X32752223Y51727137D01*
X33228280Y52876441D01*
X33228280Y54120439D01*
X32752223Y55269743D01*
X31872583Y56149383D01*
X30723279Y56625440D01*
X29479281Y56625440D01*
X28329977Y56149383D01*
X27450337Y55269743D01*
X26974280Y54120439D01*
X9028280Y54120439D01*
X8552223Y55269743D01*
X7672583Y56149383D01*
X6523279Y56625440D01*
X5279281Y56625440D01*
X4129977Y56149383D01*
X3250337Y55269743D01*
X2774280Y54120439D01*
X-3796720Y54120439D01*
X-3796720Y84320439D01*
X2774280Y84320439D01*
X2774280Y83076441D01*
X3250337Y81927137D01*
X4129977Y81047497D01*
X4595801Y80854546D01*
X4086157Y80344902D01*
X3724280Y79471255D01*
X3724280Y78525625D01*
X4086157Y77651978D01*
X4754818Y76983317D01*
X4959729Y76898440D01*
X4754818Y76813563D01*
X4086157Y76144902D01*
X3724280Y75271255D01*
X3724280Y74325625D01*
X4086157Y73451978D01*
X4754818Y72783317D01*
X4959729Y72698440D01*
X4754818Y72613563D01*
X4086157Y71944902D01*
X3724280Y71071255D01*
X3724280Y70125625D01*
X4086157Y69251978D01*
X4754818Y68583317D01*
X4959729Y68498440D01*
X4754818Y68413563D01*
X4086157Y67744902D01*
X3724280Y66871255D01*
X3724280Y65925625D01*
X4086157Y65051978D01*
X4595801Y64542334D01*
X4129977Y64349383D01*
X3250337Y63469743D01*
X2774280Y62320439D01*
X2774280Y61076441D01*
X3250337Y59927137D01*
X4129977Y59047497D01*
X5279281Y58571440D01*
X6523279Y58571440D01*
X7672583Y59047497D01*
X8552223Y59927137D01*
X9028280Y61076441D01*
X9028280Y62320439D01*
X8552223Y63469743D01*
X7672583Y64349383D01*
X7489601Y64425176D01*
X8003701Y64939276D01*
X9725999Y64939276D01*
X9900471Y64783461D01*
X10549006Y64753011D01*
X10702089Y64783461D01*
X10876561Y64939276D01*
X25125999Y64939276D01*
X25300471Y64783461D01*
X25949006Y64753011D01*
X26102089Y64783461D01*
X26276561Y64939276D01*
X25701280Y65514557D01*
X25125999Y64939276D01*
X10876561Y64939276D01*
X10301280Y65514557D01*
X9725999Y64939276D01*
X8003701Y64939276D01*
X8116403Y65051978D01*
X8478280Y65925625D01*
X8478280Y66150714D01*
X8655851Y66150714D01*
X8686301Y65997631D01*
X8842116Y65823159D01*
X9417397Y66398440D01*
X11185163Y66398440D01*
X11760444Y65823159D01*
X11916259Y65997631D01*
X11923446Y66150714D01*
X24055851Y66150714D01*
X24086301Y65997631D01*
X24242116Y65823159D01*
X24817397Y66398440D01*
X26585163Y66398440D01*
X27160444Y65823159D01*
X27316259Y65997631D01*
X27346709Y66646166D01*
X27316259Y66799249D01*
X27160444Y66973721D01*
X26585163Y66398440D01*
X24817397Y66398440D01*
X24242116Y66973721D01*
X24086301Y66799249D01*
X24055851Y66150714D01*
X11923446Y66150714D01*
X11946709Y66646166D01*
X11916259Y66799249D01*
X11760444Y66973721D01*
X11185163Y66398440D01*
X9417397Y66398440D01*
X8842116Y66973721D01*
X8686301Y66799249D01*
X8655851Y66150714D01*
X8478280Y66150714D01*
X8478280Y66871255D01*
X8116403Y67744902D01*
X8003701Y67857604D01*
X9725999Y67857604D01*
X10301280Y67282323D01*
X10876561Y67857604D01*
X25125999Y67857604D01*
X25701280Y67282323D01*
X26276561Y67857604D01*
X26102089Y68013419D01*
X25453554Y68043869D01*
X25300471Y68013419D01*
X25125999Y67857604D01*
X10876561Y67857604D01*
X10702089Y68013419D01*
X10053554Y68043869D01*
X9900471Y68013419D01*
X9725999Y67857604D01*
X8003701Y67857604D01*
X7447742Y68413563D01*
X7242831Y68498440D01*
X7447742Y68583317D01*
X8003701Y69139276D01*
X9725999Y69139276D01*
X9900471Y68983461D01*
X10549006Y68953011D01*
X10702089Y68983461D01*
X10876561Y69139276D01*
X25125999Y69139276D01*
X25300471Y68983461D01*
X25949006Y68953011D01*
X26102089Y68983461D01*
X26276561Y69139276D01*
X25701280Y69714557D01*
X25125999Y69139276D01*
X10876561Y69139276D01*
X10301280Y69714557D01*
X9725999Y69139276D01*
X8003701Y69139276D01*
X8116403Y69251978D01*
X8478280Y70125625D01*
X8478280Y70350714D01*
X8655851Y70350714D01*
X8686301Y70197631D01*
X8842116Y70023159D01*
X9417397Y70598440D01*
X11185163Y70598440D01*
X11760444Y70023159D01*
X11916259Y70197631D01*
X11923446Y70350714D01*
X24055851Y70350714D01*
X24086301Y70197631D01*
X24242116Y70023159D01*
X24817397Y70598440D01*
X26585163Y70598440D01*
X27160444Y70023159D01*
X27316259Y70197631D01*
X27346709Y70846166D01*
X27316259Y70999249D01*
X27160444Y71173721D01*
X26585163Y70598440D01*
X24817397Y70598440D01*
X24242116Y71173721D01*
X24086301Y70999249D01*
X24055851Y70350714D01*
X11923446Y70350714D01*
X11946709Y70846166D01*
X11916259Y70999249D01*
X11760444Y71173721D01*
X11185163Y70598440D01*
X9417397Y70598440D01*
X8842116Y71173721D01*
X8686301Y70999249D01*
X8655851Y70350714D01*
X8478280Y70350714D01*
X8478280Y71071255D01*
X8116403Y71944902D01*
X8003701Y72057604D01*
X9725999Y72057604D01*
X10301280Y71482323D01*
X10876561Y72057604D01*
X25125999Y72057604D01*
X25701280Y71482323D01*
X26276561Y72057604D01*
X26102089Y72213419D01*
X25453554Y72243869D01*
X25300471Y72213419D01*
X25125999Y72057604D01*
X10876561Y72057604D01*
X10702089Y72213419D01*
X10053554Y72243869D01*
X9900471Y72213419D01*
X9725999Y72057604D01*
X8003701Y72057604D01*
X7447742Y72613563D01*
X7242831Y72698440D01*
X7447742Y72783317D01*
X8003701Y73339276D01*
X9725999Y73339276D01*
X9900471Y73183461D01*
X10549006Y73153011D01*
X10702089Y73183461D01*
X10876561Y73339276D01*
X25125999Y73339276D01*
X25300471Y73183461D01*
X25949006Y73153011D01*
X26102089Y73183461D01*
X26276561Y73339276D01*
X25701280Y73914557D01*
X25125999Y73339276D01*
X10876561Y73339276D01*
X10301280Y73914557D01*
X9725999Y73339276D01*
X8003701Y73339276D01*
X8116403Y73451978D01*
X8478280Y74325625D01*
X8478280Y74550714D01*
X8655851Y74550714D01*
X8686301Y74397631D01*
X8842116Y74223159D01*
X9417397Y74798440D01*
X11185163Y74798440D01*
X11760444Y74223159D01*
X11916259Y74397631D01*
X11923446Y74550714D01*
X24055851Y74550714D01*
X24086301Y74397631D01*
X24242116Y74223159D01*
X24817397Y74798440D01*
X26585163Y74798440D01*
X27160444Y74223159D01*
X27316259Y74397631D01*
X27346709Y75046166D01*
X27316259Y75199249D01*
X27160444Y75373721D01*
X26585163Y74798440D01*
X24817397Y74798440D01*
X24242116Y75373721D01*
X24086301Y75199249D01*
X24055851Y74550714D01*
X11923446Y74550714D01*
X11946709Y75046166D01*
X11916259Y75199249D01*
X11760444Y75373721D01*
X11185163Y74798440D01*
X9417397Y74798440D01*
X8842116Y75373721D01*
X8686301Y75199249D01*
X8655851Y74550714D01*
X8478280Y74550714D01*
X8478280Y75271255D01*
X8116403Y76144902D01*
X8003701Y76257604D01*
X9725999Y76257604D01*
X10301280Y75682323D01*
X10876561Y76257604D01*
X25125999Y76257604D01*
X25701280Y75682323D01*
X26276561Y76257604D01*
X26102089Y76413419D01*
X25453554Y76443869D01*
X25300471Y76413419D01*
X25125999Y76257604D01*
X10876561Y76257604D01*
X10702089Y76413419D01*
X10053554Y76443869D01*
X9900471Y76413419D01*
X9725999Y76257604D01*
X8003701Y76257604D01*
X7447742Y76813563D01*
X7242831Y76898440D01*
X7447742Y76983317D01*
X8003701Y77539276D01*
X9725999Y77539276D01*
X9900471Y77383461D01*
X10549006Y77353011D01*
X10702089Y77383461D01*
X10876561Y77539276D01*
X25125999Y77539276D01*
X25300471Y77383461D01*
X25949006Y77353011D01*
X26102089Y77383461D01*
X26276561Y77539276D01*
X25701280Y78114557D01*
X25125999Y77539276D01*
X10876561Y77539276D01*
X10301280Y78114557D01*
X9725999Y77539276D01*
X8003701Y77539276D01*
X8116403Y77651978D01*
X8478280Y78525625D01*
X8478280Y78750714D01*
X8655851Y78750714D01*
X8686301Y78597631D01*
X8842116Y78423159D01*
X9417397Y78998440D01*
X11185163Y78998440D01*
X11760444Y78423159D01*
X11916259Y78597631D01*
X11923446Y78750714D01*
X24055851Y78750714D01*
X24086301Y78597631D01*
X24242116Y78423159D01*
X24817397Y78998440D01*
X26585163Y78998440D01*
X27160444Y78423159D01*
X27316259Y78597631D01*
X27346709Y79246166D01*
X27316259Y79399249D01*
X27160444Y79573721D01*
X26585163Y78998440D01*
X24817397Y78998440D01*
X24242116Y79573721D01*
X24086301Y79399249D01*
X24055851Y78750714D01*
X11923446Y78750714D01*
X11946709Y79246166D01*
X11916259Y79399249D01*
X11760444Y79573721D01*
X11185163Y78998440D01*
X9417397Y78998440D01*
X8842116Y79573721D01*
X8686301Y79399249D01*
X8655851Y78750714D01*
X8478280Y78750714D01*
X8478280Y79471255D01*
X8116403Y80344902D01*
X8003701Y80457604D01*
X9725999Y80457604D01*
X10301280Y79882323D01*
X10876561Y80457604D01*
X25125999Y80457604D01*
X25701280Y79882323D01*
X26276561Y80457604D01*
X26102089Y80613419D01*
X25453554Y80643869D01*
X25300471Y80613419D01*
X25125999Y80457604D01*
X10876561Y80457604D01*
X10702089Y80613419D01*
X10053554Y80643869D01*
X9900471Y80613419D01*
X9725999Y80457604D01*
X8003701Y80457604D01*
X7489601Y80971704D01*
X7672583Y81047497D01*
X8552223Y81927137D01*
X9028280Y83076441D01*
X9028280Y84320439D01*
X26974280Y84320439D01*
X26974280Y83076441D01*
X27450337Y81927137D01*
X28329977Y81047497D01*
X28512959Y80971704D01*
X27886157Y80344902D01*
X27524280Y79471255D01*
X27524280Y78525625D01*
X27886157Y77651978D01*
X28554818Y76983317D01*
X28759729Y76898440D01*
X28554818Y76813563D01*
X27886157Y76144902D01*
X27524280Y75271255D01*
X27524280Y74325625D01*
X27886157Y73451978D01*
X28554818Y72783317D01*
X28759729Y72698440D01*
X28554818Y72613563D01*
X27886157Y71944902D01*
X27524280Y71071255D01*
X27524280Y70125625D01*
X27886157Y69251978D01*
X28554818Y68583317D01*
X28759729Y68498440D01*
X28554818Y68413563D01*
X27886157Y67744902D01*
X27524280Y66871255D01*
X27524280Y65925625D01*
X27886157Y65051978D01*
X28512959Y64425176D01*
X28329977Y64349383D01*
X27450337Y63469743D01*
X26974280Y62320439D01*
X26974280Y61076441D01*
X27450337Y59927137D01*
X28329977Y59047497D01*
X29479281Y58571440D01*
X30723279Y58571440D01*
X31872583Y59047497D01*
X32752223Y59927137D01*
X33228280Y61076441D01*
X33228280Y62320439D01*
X32752223Y63469743D01*
X31872583Y64349383D01*
X31406759Y64542334D01*
X31916403Y65051978D01*
X32278280Y65925625D01*
X32278280Y66871255D01*
X31916403Y67744902D01*
X31247742Y68413563D01*
X31042831Y68498440D01*
X31247742Y68583317D01*
X31916403Y69251978D01*
X32278280Y70125625D01*
X32278280Y71071255D01*
X31916403Y71944902D01*
X31247742Y72613563D01*
X31042831Y72698440D01*
X31247742Y72783317D01*
X31916403Y73451978D01*
X32278280Y74325625D01*
X32278280Y75271255D01*
X31916403Y76144902D01*
X31247742Y76813563D01*
X31042831Y76898440D01*
X31247742Y76983317D01*
X31916403Y77651978D01*
X32278280Y78525625D01*
X32278280Y79471255D01*
X31916403Y80344902D01*
X31406759Y80854546D01*
X31872583Y81047497D01*
X32752223Y81927137D01*
X32939158Y82378440D01*
X38914280Y82378440D01*
X38914280Y75108440D01*
X38923947Y75059839D01*
X38951477Y75018637D01*
X38992679Y74991107D01*
X39034280Y74982832D01*
X39034280Y268440D01*
X39044281Y219042D01*
X39072090Y178029D01*
X41292090Y-2011971D01*
X41332679Y-2038893D01*
X41381280Y-2048560D01*
X68881280Y-2048560D01*
X68929613Y-2039003D01*
X68970878Y-2011567D01*
X71170878Y178433D01*
X71198613Y219839D01*
X71208280Y268440D01*
X71208280Y550286D01*
X137115102Y550286D01*
X137115102Y-553406D01*
X137311859Y-923214D01*
X138233513Y-1560D01*
X141769047Y-1560D01*
X142690701Y-923214D01*
X142887458Y-553406D01*
X142887458Y550286D01*
X142690701Y920094D01*
X141769047Y-1560D01*
X138233513Y-1560D01*
X137311859Y920094D01*
X137115102Y550286D01*
X71208280Y550286D01*
X71208280Y2687861D01*
X139079626Y2687861D01*
X140001280Y1766207D01*
X140922934Y2687861D01*
X140553126Y2884618D01*
X139449434Y2884618D01*
X139079626Y2687861D01*
X71208280Y2687861D01*
X71208280Y5647261D01*
X112703401Y5647261D01*
X113857205Y5293875D01*
X116145355Y5293875D01*
X117299159Y5647261D01*
X115001280Y7945139D01*
X112703401Y5647261D01*
X71208280Y5647261D01*
X71208280Y14392515D01*
X107046715Y14392515D01*
X107046715Y12104365D01*
X107400101Y10950561D01*
X109697979Y13248440D01*
X120304581Y13248440D01*
X122602459Y10950561D01*
X122955845Y12104365D01*
X122955845Y14392515D01*
X122602459Y15546319D01*
X120304581Y13248440D01*
X109697979Y13248440D01*
X107400101Y15546319D01*
X107046715Y14392515D01*
X71208280Y14392515D01*
X71208280Y20849619D01*
X112703401Y20849619D01*
X115001280Y18551741D01*
X117299159Y20849619D01*
X116145355Y21203005D01*
X113857205Y21203005D01*
X112703401Y20849619D01*
X71208280Y20849619D01*
X71208280Y28147261D01*
X112703401Y28147261D01*
X113857205Y27793875D01*
X116145355Y27793875D01*
X117299159Y28147261D01*
X115001280Y30445139D01*
X112703401Y28147261D01*
X71208280Y28147261D01*
X71208280Y36892515D01*
X107046715Y36892515D01*
X107046715Y34604365D01*
X107400101Y33450561D01*
X109697979Y35748440D01*
X120304581Y35748440D01*
X122602459Y33450561D01*
X122955845Y34604365D01*
X122955845Y36892515D01*
X122602459Y38046319D01*
X120304581Y35748440D01*
X109697979Y35748440D01*
X107400101Y38046319D01*
X107046715Y36892515D01*
X71208280Y36892515D01*
X71208280Y43349619D01*
X112703401Y43349619D01*
X115001280Y41051741D01*
X117299159Y43349619D01*
X116145355Y43703005D01*
X113857205Y43703005D01*
X112703401Y43349619D01*
X71208280Y43349619D01*
X71208280Y50647261D01*
X112703401Y50647261D01*
X113857205Y50293875D01*
X116145355Y50293875D01*
X117299159Y50647261D01*
X115001280Y52945139D01*
X112703401Y50647261D01*
X71208280Y50647261D01*
X71208280Y59392515D01*
X107046715Y59392515D01*
X107046715Y57104365D01*
X107400101Y55950561D01*
X109697979Y58248440D01*
X120304581Y58248440D01*
X122602459Y55950561D01*
X122955845Y57104365D01*
X122955845Y59392515D01*
X122602459Y60546319D01*
X120304581Y58248440D01*
X109697979Y58248440D01*
X107400101Y60546319D01*
X107046715Y59392515D01*
X71208280Y59392515D01*
X71208280Y65849619D01*
X112703401Y65849619D01*
X115001280Y63551741D01*
X117299159Y65849619D01*
X116145355Y66203005D01*
X113857205Y66203005D01*
X112703401Y65849619D01*
X71208280Y65849619D01*
X71208280Y73147261D01*
X112703401Y73147261D01*
X113857205Y72793875D01*
X116145355Y72793875D01*
X117299159Y73147261D01*
X115001280Y75445139D01*
X112703401Y73147261D01*
X71208280Y73147261D01*
X71208280Y81892515D01*
X107046715Y81892515D01*
X107046715Y79604365D01*
X107400101Y78450561D01*
X109697979Y80748440D01*
X120304581Y80748440D01*
X122602459Y78450561D01*
X122955845Y79604365D01*
X122955845Y81892515D01*
X122602459Y83046319D01*
X120304581Y80748440D01*
X109697979Y80748440D01*
X107400101Y83046319D01*
X107046715Y81892515D01*
X71208280Y81892515D01*
X71208280Y82408440D01*
X71199266Y82455434D01*
X71172301Y82497007D01*
X65477442Y88349619D01*
X112703401Y88349619D01*
X115001280Y86051741D01*
X116258558Y87309019D01*
X139079626Y87309019D01*
X139449434Y87112262D01*
X140553126Y87112262D01*
X140922934Y87309019D01*
X140001280Y88230673D01*
X139079626Y87309019D01*
X116258558Y87309019D01*
X117299159Y88349619D01*
X116145355Y88703005D01*
X113857205Y88703005D01*
X112703401Y88349619D01*
X65477442Y88349619D01*
X63952301Y89917007D01*
X63909613Y89945883D01*
X63860991Y89955440D01*
X46310991Y89915440D01*
X46261417Y89905242D01*
X46220514Y89877269D01*
X39801018Y83317784D01*
X38951477Y82468243D01*
X38923947Y82427041D01*
X38914280Y82378440D01*
X32939158Y82378440D01*
X33228280Y83076441D01*
X33228280Y84320439D01*
X32752223Y85469743D01*
X31872583Y86349383D01*
X30723279Y86825440D01*
X29479281Y86825440D01*
X28329977Y86349383D01*
X27450337Y85469743D01*
X26974280Y84320439D01*
X9028280Y84320439D01*
X8552223Y85469743D01*
X7672583Y86349383D01*
X6523279Y86825440D01*
X5279281Y86825440D01*
X4129977Y86349383D01*
X3250337Y85469743D01*
X2774280Y84320439D01*
X-3796720Y84320439D01*
X-3796720Y87309019D01*
X-920374Y87309019D01*
X-550566Y87112262D01*
X553126Y87112262D01*
X922934Y87309019D01*
X1280Y88230673D01*
X-920374Y87309019D01*
X-3796720Y87309019D01*
X-3796720Y90550286D01*
X-2884898Y90550286D01*
X-2884898Y89446594D01*
X-2688141Y89076786D01*
X-1766487Y89998440D01*
X1769047Y89998440D01*
X2690701Y89076786D01*
X2887458Y89446594D01*
X2887458Y90550286D01*
X137115102Y90550286D01*
X137115102Y89446594D01*
X137311859Y89076786D01*
X138233513Y89998440D01*
X141769047Y89998440D01*
X142690701Y89076786D01*
X142887458Y89446594D01*
X142887458Y90550286D01*
X142690701Y90920094D01*
X141769047Y89998440D01*
X138233513Y89998440D01*
X137311859Y90920094D01*
X137115102Y90550286D01*
X2887458Y90550286D01*
X2690701Y90920094D01*
X1769047Y89998440D01*
X-1766487Y89998440D01*
X-2688141Y90920094D01*
X-2884898Y90550286D01*
X-3796720Y90550286D01*
X-3796720Y92500556D01*
X-3609415Y92687861D01*
X-920374Y92687861D01*
X1280Y91766207D01*
X922934Y92687861D01*
X139079626Y92687861D01*
X140001280Y91766207D01*
X140922934Y92687861D01*
X140553126Y92884618D01*
X139449434Y92884618D01*
X139079626Y92687861D01*
X922934Y92687861D01*
X553126Y92884618D01*
X-550566Y92884618D01*
X-920374Y92687861D01*
X-3609415Y92687861D01*
X-2500835Y93796440D01*
X142503396Y93796440D01*
X143799280Y92500555D01*
D15*
G36*
X71019280Y82383254D02*
X71019280Y294204D01*
X68855681Y-1859560D01*
X41406714Y-1859560D01*
X39223280Y294368D01*
X39223280Y12599352D01*
X44439280Y12599352D01*
X44439280Y8397528D01*
X46047249Y4515547D01*
X49018387Y1544409D01*
X52900368Y-63560D01*
X57102192Y-63560D01*
X60984173Y1544409D01*
X63955311Y4515547D01*
X65563280Y8397528D01*
X65563280Y12599352D01*
X63955311Y16481333D01*
X60984173Y19452471D01*
X57102192Y21060440D01*
X52900368Y21060440D01*
X49018387Y19452471D01*
X46047249Y16481333D01*
X44439280Y12599352D01*
X39223280Y12599352D01*
X39223280Y35099352D01*
X44439280Y35099352D01*
X44439280Y30897528D01*
X46047249Y27015547D01*
X49018387Y24044409D01*
X52900368Y22436440D01*
X57102192Y22436440D01*
X60984173Y24044409D01*
X63955311Y27015547D01*
X65563280Y30897528D01*
X65563280Y35099352D01*
X63955311Y38981333D01*
X60984173Y41952471D01*
X57102192Y43560440D01*
X52900368Y43560440D01*
X49018387Y41952471D01*
X46047249Y38981333D01*
X44439280Y35099352D01*
X39223280Y35099352D01*
X39223280Y57599352D01*
X44439280Y57599352D01*
X44439280Y53397528D01*
X46047249Y49515547D01*
X49018387Y46544409D01*
X52900368Y44936440D01*
X57102192Y44936440D01*
X60984173Y46544409D01*
X63955311Y49515547D01*
X65563280Y53397528D01*
X65563280Y57599352D01*
X63955311Y61481333D01*
X60984173Y64452471D01*
X57102192Y66060440D01*
X52900368Y66060440D01*
X49018387Y64452471D01*
X46047249Y61481333D01*
X44439280Y57599352D01*
X39223280Y57599352D01*
X39223280Y75118440D01*
X39218561Y75142166D01*
X39205121Y75162281D01*
X39185006Y75175721D01*
X39161280Y75180440D01*
X39146243Y75178589D01*
X39113647Y75170440D01*
X39103280Y75170440D01*
X39103280Y80099352D01*
X44439280Y80099352D01*
X44439280Y75897528D01*
X46047249Y72015547D01*
X49018387Y69044409D01*
X52900368Y67436440D01*
X57102192Y67436440D01*
X60984173Y69044409D01*
X63955311Y72015547D01*
X65563280Y75897528D01*
X65563280Y80099352D01*
X63955311Y83981333D01*
X60984173Y86952471D01*
X57102192Y88560440D01*
X52900368Y88560440D01*
X49018387Y86952471D01*
X46047249Y83981333D01*
X44439280Y80099352D01*
X39103280Y80099352D01*
X39103280Y82352758D01*
X39935121Y83184599D01*
X39935591Y83185075D01*
X46337412Y89726499D01*
X63835160Y89766380D01*
X71019280Y82383254D01*
X71019280Y82383254D01*
G37*
X71019280Y82383254D02*
X71019280Y294204D01*
X68855681Y-1859560D01*
X41406714Y-1859560D01*
X39223280Y294368D01*
X39223280Y12599352D01*
X44439280Y12599352D01*
X44439280Y8397528D01*
X46047249Y4515547D01*
X49018387Y1544409D01*
X52900368Y-63560D01*
X57102192Y-63560D01*
X60984173Y1544409D01*
X63955311Y4515547D01*
X65563280Y8397528D01*
X65563280Y12599352D01*
X63955311Y16481333D01*
X60984173Y19452471D01*
X57102192Y21060440D01*
X52900368Y21060440D01*
X49018387Y19452471D01*
X46047249Y16481333D01*
X44439280Y12599352D01*
X39223280Y12599352D01*
X39223280Y35099352D01*
X44439280Y35099352D01*
X44439280Y30897528D01*
X46047249Y27015547D01*
X49018387Y24044409D01*
X52900368Y22436440D01*
X57102192Y22436440D01*
X60984173Y24044409D01*
X63955311Y27015547D01*
X65563280Y30897528D01*
X65563280Y35099352D01*
X63955311Y38981333D01*
X60984173Y41952471D01*
X57102192Y43560440D01*
X52900368Y43560440D01*
X49018387Y41952471D01*
X46047249Y38981333D01*
X44439280Y35099352D01*
X39223280Y35099352D01*
X39223280Y57599352D01*
X44439280Y57599352D01*
X44439280Y53397528D01*
X46047249Y49515547D01*
X49018387Y46544409D01*
X52900368Y44936440D01*
X57102192Y44936440D01*
X60984173Y46544409D01*
X63955311Y49515547D01*
X65563280Y53397528D01*
X65563280Y57599352D01*
X63955311Y61481333D01*
X60984173Y64452471D01*
X57102192Y66060440D01*
X52900368Y66060440D01*
X49018387Y64452471D01*
X46047249Y61481333D01*
X44439280Y57599352D01*
X39223280Y57599352D01*
X39223280Y75118440D01*
X39218561Y75142166D01*
X39205121Y75162281D01*
X39185006Y75175721D01*
X39161280Y75180440D01*
X39146243Y75178589D01*
X39113647Y75170440D01*
X39103280Y75170440D01*
X39103280Y80099352D01*
X44439280Y80099352D01*
X44439280Y75897528D01*
X46047249Y72015547D01*
X49018387Y69044409D01*
X52900368Y67436440D01*
X57102192Y67436440D01*
X60984173Y69044409D01*
X63955311Y72015547D01*
X65563280Y75897528D01*
X65563280Y80099352D01*
X63955311Y83981333D01*
X60984173Y86952471D01*
X57102192Y88560440D01*
X52900368Y88560440D01*
X49018387Y86952471D01*
X46047249Y83981333D01*
X44439280Y80099352D01*
X39103280Y80099352D01*
X39103280Y82352758D01*
X39935121Y83184599D01*
X39935591Y83185075D01*
X46337412Y89726499D01*
X63835160Y89766380D01*
X71019280Y82383254D01*
G04 #@! TD*
M02*
